FILE_TYPE = MACRO_DRAWING;
SET COLOR_WIRE YELLOW;
SET COLOR_PROP ORANGE;
SET COLOR_DOT WHITE;
SET COLOR_ARC YELLOW;
SET COLOR_BODY GREEN;
SET COLOR_NOTE PURPLE;
SET PROP_DISPLAY VALUE;
SET PAGE_NUMBER P407;
FORCEADD OFFPAGE..1
(-4325 2175);
FORCEPROP 2 LAST $XR0 287 
J 0
(-4607 2175);
DISPLAY 0.638298 (-4607 2175);
PAINT MONO (-4607 2175);
FORCEPROP 2 LAST CDS_LIB standard
J 0
(-4325 2175);
DISPLAY INVISIBLE (-4325 2175);
FORCEPROP 1 LAST OFFPAGE TRUE
J 0
(-4000 2050);
DISPLAY 0.872340 (-4000 2050);
DISPLAY INVISIBLE (-4000 2050);
FORCEPROP 1 LAST COMMENT_BODY TRUE
J 0
(-4200 2075);
DISPLAY 0.872340 (-4200 2075);
PAINT GREEN (-4200 2075);
DISPLAY INVISIBLE (-4200 2075);
FORCEPROP 2 LAST PATH I1
J 0
(-4575 2225);
DISPLAY 0.680851 (-4575 2225);
DISPLAY INVISIBLE (-4575 2225);
FORCEADD TAP..1
R 2
(-3125 1000);
FORCEPROP 3 LASTPIN (-3075 1000) SIG_NAME P5E_CPU0_P1_TX_BUF_DP<6>
J 0
(-3065 1010);
DISPLAY 0.659574 (-3065 1010);
PAINT MONO (-3065 1010);
DISPLAY INVISIBLE (-3065 1010);
FORCEPROP 1 LASTPIN (-3075 1000) BN 6
J 2
(-3063 1008);
DISPLAY 0.680851 (-3063 1008);
PAINT GREEN (-3063 1008);
FORCEPROP 2 LAST CDS_LIB standard
J 0
(-3125 1000);
DISPLAY INVISIBLE (-3125 1000);
FORCEPROP 1 LAST BODY_TYPE PLUMBING
J 2
(-3125 1050);
DISPLAY 0.872340 (-3125 1050);
PAINT GREEN (-3125 1050);
DISPLAY INVISIBLE (-3125 1050);
FORCEPROP 1 LAST HDL_TAP TRUE
J 2
(-3450 875);
DISPLAY 0.872340 (-3450 875);
DISPLAY INVISIBLE (-3450 875);
FORCEPROP 1 LAST PATH I10
J 2
(-3123 1000);
DISPLAY 0.872340 (-3123 1000);
PAINT GREEN (-3123 1000);
DISPLAY INVISIBLE (-3123 1000);
FORCEADD TAP..1
R 2
(-7650 2000);
FORCEPROP 3 LASTPIN (-7600 2000) SIG_NAME P5E_CPU0_P1_TX_BUF_DP<9>
J 0
(-7590 2010);
DISPLAY 0.659574 (-7590 2010);
PAINT MONO (-7590 2010);
DISPLAY INVISIBLE (-7590 2010);
FORCEPROP 1 LASTPIN (-7600 2000) BN 9
J 2
(-7588 2008);
DISPLAY 0.680851 (-7588 2008);
PAINT GREEN (-7588 2008);
FORCEPROP 2 LAST CDS_LIB standard
J 0
(-7650 2000);
DISPLAY INVISIBLE (-7650 2000);
FORCEPROP 1 LAST BODY_TYPE PLUMBING
J 2
(-7650 2050);
DISPLAY 0.872340 (-7650 2050);
PAINT GREEN (-7650 2050);
DISPLAY INVISIBLE (-7650 2050);
FORCEPROP 1 LAST HDL_TAP TRUE
J 2
(-7975 1875);
DISPLAY 0.872340 (-7975 1875);
DISPLAY INVISIBLE (-7975 1875);
FORCEPROP 1 LAST PATH I100
J 2
(-7648 2000);
DISPLAY 0.872340 (-7648 2000);
PAINT GREEN (-7648 2000);
DISPLAY INVISIBLE (-7648 2000);
FORCEADD TAP..1
R 2
(-7650 2200);
FORCEPROP 3 LASTPIN (-7600 2200) SIG_NAME P5E_CPU0_P1_TX_BUF_DP<8>
J 0
(-7590 2210);
DISPLAY 0.659574 (-7590 2210);
PAINT MONO (-7590 2210);
DISPLAY INVISIBLE (-7590 2210);
FORCEPROP 1 LASTPIN (-7600 2200) BN 8
J 2
(-7588 2208);
DISPLAY 0.680851 (-7588 2208);
PAINT GREEN (-7588 2208);
FORCEPROP 2 LAST CDS_LIB standard
J 0
(-7650 2200);
DISPLAY INVISIBLE (-7650 2200);
FORCEPROP 1 LAST BODY_TYPE PLUMBING
J 2
(-7650 2250);
DISPLAY 0.872340 (-7650 2250);
PAINT GREEN (-7650 2250);
DISPLAY INVISIBLE (-7650 2250);
FORCEPROP 1 LAST HDL_TAP TRUE
J 2
(-7975 2075);
DISPLAY 0.872340 (-7975 2075);
DISPLAY INVISIBLE (-7975 2075);
FORCEPROP 1 LAST PATH I101
J 2
(-7648 2200);
DISPLAY 0.872340 (-7648 2200);
PAINT GREEN (-7648 2200);
DISPLAY INVISIBLE (-7648 2200);
FORCEADD Q_CAP_DIFFBUS..2
R 2
(-6925 2000);
FORCEPROP 1 LAST LOCATION C6551
J 2
(-6650 2000);
DISPLAY 0.723404 (-6650 2000);
PAINT GREEN (-6650 2000);
FORCEPROP 2 LAST $SEC 1
J 2
(-6750 2075);
DISPLAY 0.680851 (-6750 2075);
PAINT MONO (-6750 2075);
DISPLAY INVISIBLE (-6750 2075);
FORCEPROP 2 LAST CDS_SEC 1
J 2
(-6750 2075);
DISPLAY 0.680851 (-6750 2075);
DISPLAY INVISIBLE (-6750 2075);
FORCEPROP 2 LASTPIN (-6850 2000) $PN 1
J 0
(-6840 2010);
DISPLAY 0.808511 (-6840 2010);
FORCEPROP 2 LASTPIN (-7000 2000) $PN 2
J 2
(-7010 2010);
DISPLAY 0.808511 (-7010 2010);
FORCEPROP 2 LAST VALUE DIFF BUS_0.22UF
J 2
(-7075 2000);
DISPLAY 0.553191 (-7075 2000);
FORCEPROP 2 LAST TOLERANCE 20%
J 2
(-7000 2050);
DISPLAY 0.553191 (-7000 2050);
DISPLAY INVISIBLE (-7000 2050);
FORCEPROP 2 LAST PACK_TYPE C0201
J 2
(-7100 2050);
DISPLAY 0.553191 (-7100 2050);
DISPLAY INVISIBLE (-7100 2050);
FORCEPROP 1 LAST MATERIAL X6S
J 2
(-6916 2079);
DISPLAY 0.574468 (-6916 2079);
PAINT GREEN (-6916 2079);
DISPLAY INVISIBLE (-6916 2079);
FORCEPROP 2 LAST VOLTAGE 6.3V
J 2
(-7275 2050);
DISPLAY 0.553191 (-7275 2050);
DISPLAY INVISIBLE (-7275 2050);
FORCEPROP 1 LAST PIN_NAMES_ROTATE TRUE
J 2
(-6925 2000);
DISPLAY 0.489362 (-6925 2000);
PAINT GREEN (-6925 2000);
DISPLAY INVISIBLE (-6925 2000);
FORCEPROP 2 LAST CDS_LIB pure_quanta
J 2
(-6925 2000);
DISPLAY INVISIBLE (-6925 2000);
FORCEPROP 1 LAST CDS_LMAN_SYM_OUTLINE -25,50,25,-50
J 2
(-6925 2000);
DISPLAY 0.468085 (-6925 2000);
PAINT GREEN (-6925 2000);
DISPLAY INVISIBLE (-6925 2000);
FORCEPROP 1 LAST PATH I102
J 2
(-6925 2000);
DISPLAY 0.723404 (-6925 2000);
DISPLAY INVISIBLE (-6925 2000);
FORCEPROP 1 LAST PART_NUMBER SP_CH4221MEE01
J 2
(-7041 2088);
DISPLAY 0.574468 (-7041 2088);
PAINT GREEN (-7041 2088);
DISPLAY INVISIBLE (-7041 2088);
FORCEPROP 1 LAST LOCATION C6551
J 0
(-6675 2075);
DISPLAY 1.021277 (-6675 2075);
DISPLAY INVISIBLE (-6675 2075);
FORCEADD Q_CAP_DIFFBUS..2
R 2
(-6925 1950);
FORCEPROP 1 LAST LOCATION C6552
J 2
(-6650 1950);
DISPLAY 0.723404 (-6650 1950);
PAINT GREEN (-6650 1950);
FORCEPROP 2 LAST $SEC 1
J 2
(-6750 2025);
DISPLAY 0.680851 (-6750 2025);
PAINT MONO (-6750 2025);
DISPLAY INVISIBLE (-6750 2025);
FORCEPROP 2 LAST CDS_SEC 1
J 2
(-6750 2025);
DISPLAY 0.680851 (-6750 2025);
DISPLAY INVISIBLE (-6750 2025);
FORCEPROP 2 LASTPIN (-6850 1950) $PN 1
J 0
(-6840 1960);
DISPLAY 0.808511 (-6840 1960);
FORCEPROP 2 LASTPIN (-7000 1950) $PN 2
J 2
(-7010 1960);
DISPLAY 0.808511 (-7010 1960);
FORCEPROP 2 LAST VALUE DIFF BUS_0.22UF
J 2
(-7075 1950);
DISPLAY 0.553191 (-7075 1950);
FORCEPROP 2 LAST TOLERANCE 20%
J 2
(-7000 2000);
DISPLAY 0.553191 (-7000 2000);
DISPLAY INVISIBLE (-7000 2000);
FORCEPROP 2 LAST PACK_TYPE C0201
J 2
(-7100 2000);
DISPLAY 0.553191 (-7100 2000);
DISPLAY INVISIBLE (-7100 2000);
FORCEPROP 1 LAST MATERIAL X6S
J 2
(-6916 2029);
DISPLAY 0.574468 (-6916 2029);
PAINT GREEN (-6916 2029);
DISPLAY INVISIBLE (-6916 2029);
FORCEPROP 2 LAST VOLTAGE 6.3V
J 2
(-7275 2000);
DISPLAY 0.553191 (-7275 2000);
DISPLAY INVISIBLE (-7275 2000);
FORCEPROP 1 LAST PIN_NAMES_ROTATE TRUE
J 2
(-6925 1950);
DISPLAY 0.489362 (-6925 1950);
PAINT GREEN (-6925 1950);
DISPLAY INVISIBLE (-6925 1950);
FORCEPROP 2 LAST CDS_LIB pure_quanta
J 2
(-6925 1950);
DISPLAY INVISIBLE (-6925 1950);
FORCEPROP 1 LAST CDS_LMAN_SYM_OUTLINE -25,50,25,-50
J 2
(-6925 1950);
DISPLAY 0.468085 (-6925 1950);
PAINT GREEN (-6925 1950);
DISPLAY INVISIBLE (-6925 1950);
FORCEPROP 1 LAST PATH I103
J 2
(-6925 1950);
DISPLAY 0.723404 (-6925 1950);
DISPLAY INVISIBLE (-6925 1950);
FORCEPROP 1 LAST PART_NUMBER SP_CH4221MEE01
J 2
(-7041 2038);
DISPLAY 0.574468 (-7041 2038);
PAINT GREEN (-7041 2038);
DISPLAY INVISIBLE (-7041 2038);
FORCEPROP 1 LAST LOCATION C6552
J 0
(-6675 2025);
DISPLAY 1.021277 (-6675 2025);
DISPLAY INVISIBLE (-6675 2025);
FORCEADD Q_CAP_DIFFBUS..2
R 2
(-6925 2150);
FORCEPROP 1 LAST LOCATION C6550
J 2
(-6650 2150);
DISPLAY 0.723404 (-6650 2150);
PAINT GREEN (-6650 2150);
FORCEPROP 2 LAST $SEC 1
J 2
(-6750 2225);
DISPLAY 0.680851 (-6750 2225);
PAINT MONO (-6750 2225);
DISPLAY INVISIBLE (-6750 2225);
FORCEPROP 2 LAST CDS_SEC 1
J 2
(-6750 2225);
DISPLAY 0.680851 (-6750 2225);
DISPLAY INVISIBLE (-6750 2225);
FORCEPROP 2 LASTPIN (-6850 2150) $PN 1
J 0
(-6840 2160);
DISPLAY 0.808511 (-6840 2160);
FORCEPROP 2 LASTPIN (-7000 2150) $PN 2
J 2
(-7010 2160);
DISPLAY 0.808511 (-7010 2160);
FORCEPROP 2 LAST VALUE DIFF BUS_0.22UF
J 2
(-7075 2150);
DISPLAY 0.553191 (-7075 2150);
FORCEPROP 2 LAST TOLERANCE 20%
J 2
(-7000 2200);
DISPLAY 0.553191 (-7000 2200);
DISPLAY INVISIBLE (-7000 2200);
FORCEPROP 2 LAST PACK_TYPE C0201
J 2
(-7100 2200);
DISPLAY 0.553191 (-7100 2200);
DISPLAY INVISIBLE (-7100 2200);
FORCEPROP 1 LAST MATERIAL X6S
J 2
(-6916 2229);
DISPLAY 0.574468 (-6916 2229);
PAINT GREEN (-6916 2229);
DISPLAY INVISIBLE (-6916 2229);
FORCEPROP 2 LAST VOLTAGE 6.3V
J 2
(-7275 2200);
DISPLAY 0.553191 (-7275 2200);
DISPLAY INVISIBLE (-7275 2200);
FORCEPROP 1 LAST PIN_NAMES_ROTATE TRUE
J 2
(-6925 2150);
DISPLAY 0.489362 (-6925 2150);
PAINT GREEN (-6925 2150);
DISPLAY INVISIBLE (-6925 2150);
FORCEPROP 2 LAST CDS_LIB pure_quanta
J 2
(-6925 2150);
DISPLAY INVISIBLE (-6925 2150);
FORCEPROP 1 LAST CDS_LMAN_SYM_OUTLINE -25,50,25,-50
J 2
(-6925 2150);
DISPLAY 0.468085 (-6925 2150);
PAINT GREEN (-6925 2150);
DISPLAY INVISIBLE (-6925 2150);
FORCEPROP 1 LAST PATH I104
J 2
(-6925 2150);
DISPLAY 0.723404 (-6925 2150);
DISPLAY INVISIBLE (-6925 2150);
FORCEPROP 1 LAST PART_NUMBER SP_CH4221MEE01
J 2
(-7041 2238);
DISPLAY 0.574468 (-7041 2238);
PAINT GREEN (-7041 2238);
DISPLAY INVISIBLE (-7041 2238);
FORCEPROP 1 LAST LOCATION C6550
J 0
(-6675 2225);
DISPLAY 1.021277 (-6675 2225);
DISPLAY INVISIBLE (-6675 2225);
FORCEADD Q_CAP_DIFFBUS..2
R 2
(-6925 2200);
FORCEPROP 1 LAST LOCATION C6549
J 2
(-6650 2200);
DISPLAY 0.723404 (-6650 2200);
PAINT GREEN (-6650 2200);
FORCEPROP 2 LAST $SEC 1
J 2
(-6750 2275);
DISPLAY 0.680851 (-6750 2275);
PAINT MONO (-6750 2275);
DISPLAY INVISIBLE (-6750 2275);
FORCEPROP 2 LAST CDS_SEC 1
J 2
(-6750 2275);
DISPLAY 0.680851 (-6750 2275);
DISPLAY INVISIBLE (-6750 2275);
FORCEPROP 2 LASTPIN (-6850 2200) $PN 1
J 0
(-6840 2210);
DISPLAY 0.808511 (-6840 2210);
FORCEPROP 2 LASTPIN (-7000 2200) $PN 2
J 2
(-7010 2210);
DISPLAY 0.808511 (-7010 2210);
FORCEPROP 2 LAST TOLERANCE 20%
J 2
(-6875 2350);
DISPLAY 0.553191 (-6875 2350);
PAINT GREEN (-6875 2350);
FORCEPROP 1 LAST MATERIAL X6S
J 2
(-7016 2404);
DISPLAY 0.574468 (-7016 2404);
PAINT GREEN (-7016 2404);
FORCEPROP 2 LAST PACK_TYPE C0201
J 2
(-6975 2350);
DISPLAY 0.553191 (-6975 2350);
PAINT GREEN (-6975 2350);
FORCEPROP 2 LAST VOLTAGE 6.3V
J 2
(-6750 2350);
DISPLAY 0.553191 (-6750 2350);
PAINT GREEN (-6750 2350);
FORCEPROP 2 LAST VALUE DIFF BUS_0.22UF
J 2
(-7075 2200);
DISPLAY 0.553191 (-7075 2200);
FORCEPROP 1 LAST PIN_NAMES_ROTATE TRUE
J 2
(-6925 2200);
DISPLAY 0.489362 (-6925 2200);
PAINT GREEN (-6925 2200);
DISPLAY INVISIBLE (-6925 2200);
FORCEPROP 1 LAST CDS_LMAN_SYM_OUTLINE -25,50,25,-50
J 2
(-6925 2200);
DISPLAY 0.468085 (-6925 2200);
PAINT GREEN (-6925 2200);
DISPLAY INVISIBLE (-6925 2200);
FORCEPROP 2 LAST CDS_LIB pure_quanta
J 2
(-6925 2200);
DISPLAY INVISIBLE (-6925 2200);
FORCEPROP 1 LAST PATH I105
J 2
(-6925 2200);
DISPLAY 0.723404 (-6925 2200);
DISPLAY INVISIBLE (-6925 2200);
FORCEPROP 1 LAST PART_NUMBER SP_CH4221MEE01
J 2
(-6741 2288);
DISPLAY 0.574468 (-6741 2288);
PAINT GREEN (-6741 2288);
DISPLAY INVISIBLE (-6741 2288);
FORCEPROP 1 LAST LOCATION C6549
J 0
(-6675 2275);
DISPLAY 1.021277 (-6675 2275);
DISPLAY INVISIBLE (-6675 2275);
FORCEADD TAP..1
(-6375 800);
FORCEPROP 3 LASTPIN (-6425 800) SIG_NAME P5E_CPU0_P1_TX_BUF_C_DP<15>
J 0
(-6415 810);
DISPLAY 0.659574 (-6415 810);
PAINT MONO (-6415 810);
DISPLAY INVISIBLE (-6415 810);
FORCEPROP 1 LASTPIN (-6425 800) BN 15
J 0
(-6437 808);
DISPLAY 0.680851 (-6437 808);
PAINT GREEN (-6437 808);
FORCEPROP 2 LAST CDS_LIB standard
J 0
(-6375 800);
DISPLAY INVISIBLE (-6375 800);
FORCEPROP 1 LAST BODY_TYPE PLUMBING
J 0
(-6375 850);
DISPLAY 0.872340 (-6375 850);
PAINT GREEN (-6375 850);
DISPLAY INVISIBLE (-6375 850);
FORCEPROP 1 LAST HDL_TAP TRUE
J 0
(-6050 675);
DISPLAY 0.872340 (-6050 675);
DISPLAY INVISIBLE (-6050 675);
FORCEPROP 1 LAST PATH I106
J 0
(-6377 800);
DISPLAY 0.872340 (-6377 800);
PAINT GREEN (-6377 800);
DISPLAY INVISIBLE (-6377 800);
FORCEADD TAP..1
(-6175 750);
FORCEPROP 3 LASTPIN (-6225 750) SIG_NAME P5E_CPU0_P1_TX_BUF_C_DN<15>
J 0
(-6215 760);
DISPLAY 0.659574 (-6215 760);
PAINT MONO (-6215 760);
DISPLAY INVISIBLE (-6215 760);
FORCEPROP 1 LASTPIN (-6225 750) BN 15
J 0
(-6237 758);
DISPLAY 0.680851 (-6237 758);
PAINT GREEN (-6237 758);
FORCEPROP 2 LAST CDS_LIB standard
J 0
(-6175 750);
DISPLAY INVISIBLE (-6175 750);
FORCEPROP 1 LAST BODY_TYPE PLUMBING
J 0
(-6175 800);
DISPLAY 0.872340 (-6175 800);
PAINT GREEN (-6175 800);
DISPLAY INVISIBLE (-6175 800);
FORCEPROP 1 LAST HDL_TAP TRUE
J 0
(-5850 625);
DISPLAY 0.872340 (-5850 625);
DISPLAY INVISIBLE (-5850 625);
FORCEPROP 1 LAST PATH I107
J 0
(-6177 750);
DISPLAY 0.872340 (-6177 750);
PAINT GREEN (-6177 750);
DISPLAY INVISIBLE (-6177 750);
FORCEADD TAP..1
(-6375 1000);
FORCEPROP 3 LASTPIN (-6425 1000) SIG_NAME P5E_CPU0_P1_TX_BUF_C_DP<14>
J 0
(-6415 1010);
DISPLAY 0.659574 (-6415 1010);
PAINT MONO (-6415 1010);
DISPLAY INVISIBLE (-6415 1010);
FORCEPROP 1 LASTPIN (-6425 1000) BN 14
J 0
(-6437 1008);
DISPLAY 0.680851 (-6437 1008);
PAINT GREEN (-6437 1008);
FORCEPROP 2 LAST CDS_LIB standard
J 0
(-6375 1000);
DISPLAY INVISIBLE (-6375 1000);
FORCEPROP 1 LAST BODY_TYPE PLUMBING
J 0
(-6375 1050);
DISPLAY 0.872340 (-6375 1050);
PAINT GREEN (-6375 1050);
DISPLAY INVISIBLE (-6375 1050);
FORCEPROP 1 LAST HDL_TAP TRUE
J 0
(-6050 875);
DISPLAY 0.872340 (-6050 875);
DISPLAY INVISIBLE (-6050 875);
FORCEPROP 1 LAST PATH I108
J 0
(-6377 1000);
DISPLAY 0.872340 (-6377 1000);
PAINT GREEN (-6377 1000);
DISPLAY INVISIBLE (-6377 1000);
FORCEADD TAP..1
(-6375 1200);
FORCEPROP 3 LASTPIN (-6425 1200) SIG_NAME P5E_CPU0_P1_TX_BUF_C_DP<13>
J 0
(-6415 1210);
DISPLAY 0.659574 (-6415 1210);
PAINT MONO (-6415 1210);
DISPLAY INVISIBLE (-6415 1210);
FORCEPROP 1 LASTPIN (-6425 1200) BN 13
J 0
(-6437 1208);
DISPLAY 0.680851 (-6437 1208);
PAINT GREEN (-6437 1208);
FORCEPROP 2 LAST CDS_LIB standard
J 0
(-6375 1200);
DISPLAY INVISIBLE (-6375 1200);
FORCEPROP 1 LAST BODY_TYPE PLUMBING
J 0
(-6375 1250);
DISPLAY 0.872340 (-6375 1250);
PAINT GREEN (-6375 1250);
DISPLAY INVISIBLE (-6375 1250);
FORCEPROP 1 LAST HDL_TAP TRUE
J 0
(-6050 1075);
DISPLAY 0.872340 (-6050 1075);
DISPLAY INVISIBLE (-6050 1075);
FORCEPROP 1 LAST PATH I109
J 0
(-6377 1200);
DISPLAY 0.872340 (-6377 1200);
PAINT GREEN (-6377 1200);
DISPLAY INVISIBLE (-6377 1200);
FORCEADD TAP..1
R 2
(-3125 1200);
FORCEPROP 3 LASTPIN (-3075 1200) SIG_NAME P5E_CPU0_P1_TX_BUF_DP<5>
J 0
(-3065 1210);
DISPLAY 0.659574 (-3065 1210);
PAINT MONO (-3065 1210);
DISPLAY INVISIBLE (-3065 1210);
FORCEPROP 1 LASTPIN (-3075 1200) BN 5
J 2
(-3063 1208);
DISPLAY 0.680851 (-3063 1208);
PAINT GREEN (-3063 1208);
FORCEPROP 2 LAST CDS_LIB standard
J 0
(-3125 1200);
DISPLAY INVISIBLE (-3125 1200);
FORCEPROP 1 LAST BODY_TYPE PLUMBING
J 2
(-3125 1250);
DISPLAY 0.872340 (-3125 1250);
PAINT GREEN (-3125 1250);
DISPLAY INVISIBLE (-3125 1250);
FORCEPROP 1 LAST HDL_TAP TRUE
J 2
(-3450 1075);
DISPLAY 0.872340 (-3450 1075);
DISPLAY INVISIBLE (-3450 1075);
FORCEPROP 1 LAST PATH I11
J 2
(-3123 1200);
DISPLAY 0.872340 (-3123 1200);
PAINT GREEN (-3123 1200);
DISPLAY INVISIBLE (-3123 1200);
FORCEADD TAP..1
(-6175 950);
FORCEPROP 3 LASTPIN (-6225 950) SIG_NAME P5E_CPU0_P1_TX_BUF_C_DN<14>
J 0
(-6215 960);
DISPLAY 0.659574 (-6215 960);
PAINT MONO (-6215 960);
DISPLAY INVISIBLE (-6215 960);
FORCEPROP 1 LASTPIN (-6225 950) BN 14
J 0
(-6237 958);
DISPLAY 0.680851 (-6237 958);
PAINT GREEN (-6237 958);
FORCEPROP 2 LAST CDS_LIB standard
J 0
(-6175 950);
DISPLAY INVISIBLE (-6175 950);
FORCEPROP 1 LAST BODY_TYPE PLUMBING
J 0
(-6175 1000);
DISPLAY 0.872340 (-6175 1000);
PAINT GREEN (-6175 1000);
DISPLAY INVISIBLE (-6175 1000);
FORCEPROP 1 LAST HDL_TAP TRUE
J 0
(-5850 825);
DISPLAY 0.872340 (-5850 825);
DISPLAY INVISIBLE (-5850 825);
FORCEPROP 1 LAST PATH I110
J 0
(-6177 950);
DISPLAY 0.872340 (-6177 950);
PAINT GREEN (-6177 950);
DISPLAY INVISIBLE (-6177 950);
FORCEADD TAP..1
(-6175 1150);
FORCEPROP 3 LASTPIN (-6225 1150) SIG_NAME P5E_CPU0_P1_TX_BUF_C_DN<13>
J 0
(-6215 1160);
DISPLAY 0.659574 (-6215 1160);
PAINT MONO (-6215 1160);
DISPLAY INVISIBLE (-6215 1160);
FORCEPROP 1 LASTPIN (-6225 1150) BN 13
J 0
(-6237 1158);
DISPLAY 0.680851 (-6237 1158);
PAINT GREEN (-6237 1158);
FORCEPROP 2 LAST CDS_LIB standard
J 0
(-6175 1150);
DISPLAY INVISIBLE (-6175 1150);
FORCEPROP 1 LAST BODY_TYPE PLUMBING
J 0
(-6175 1200);
DISPLAY 0.872340 (-6175 1200);
PAINT GREEN (-6175 1200);
DISPLAY INVISIBLE (-6175 1200);
FORCEPROP 1 LAST HDL_TAP TRUE
J 0
(-5850 1025);
DISPLAY 0.872340 (-5850 1025);
DISPLAY INVISIBLE (-5850 1025);
FORCEPROP 1 LAST PATH I111
J 0
(-6177 1150);
DISPLAY 0.872340 (-6177 1150);
PAINT GREEN (-6177 1150);
DISPLAY INVISIBLE (-6177 1150);
FORCEADD TAP..1
(-6175 1350);
FORCEPROP 3 LASTPIN (-6225 1350) SIG_NAME P5E_CPU0_P1_TX_BUF_C_DN<12>
J 0
(-6215 1360);
DISPLAY 0.659574 (-6215 1360);
PAINT MONO (-6215 1360);
DISPLAY INVISIBLE (-6215 1360);
FORCEPROP 1 LASTPIN (-6225 1350) BN 12
J 0
(-6237 1358);
DISPLAY 0.680851 (-6237 1358);
PAINT GREEN (-6237 1358);
FORCEPROP 2 LAST CDS_LIB standard
J 0
(-6175 1350);
DISPLAY INVISIBLE (-6175 1350);
FORCEPROP 1 LAST BODY_TYPE PLUMBING
J 0
(-6175 1400);
DISPLAY 0.872340 (-6175 1400);
PAINT GREEN (-6175 1400);
DISPLAY INVISIBLE (-6175 1400);
FORCEPROP 1 LAST HDL_TAP TRUE
J 0
(-5850 1225);
DISPLAY 0.872340 (-5850 1225);
DISPLAY INVISIBLE (-5850 1225);
FORCEPROP 1 LAST PATH I112
J 0
(-6177 1350);
DISPLAY 0.872340 (-6177 1350);
PAINT GREEN (-6177 1350);
DISPLAY INVISIBLE (-6177 1350);
FORCEADD TAP..1
(-6375 1400);
FORCEPROP 3 LASTPIN (-6425 1400) SIG_NAME P5E_CPU0_P1_TX_BUF_C_DP<12>
J 0
(-6415 1410);
DISPLAY 0.659574 (-6415 1410);
PAINT MONO (-6415 1410);
DISPLAY INVISIBLE (-6415 1410);
FORCEPROP 1 LASTPIN (-6425 1400) BN 12
J 0
(-6437 1408);
DISPLAY 0.680851 (-6437 1408);
PAINT GREEN (-6437 1408);
FORCEPROP 2 LAST CDS_LIB standard
J 0
(-6375 1400);
DISPLAY INVISIBLE (-6375 1400);
FORCEPROP 1 LAST BODY_TYPE PLUMBING
J 0
(-6375 1450);
DISPLAY 0.872340 (-6375 1450);
PAINT GREEN (-6375 1450);
DISPLAY INVISIBLE (-6375 1450);
FORCEPROP 1 LAST HDL_TAP TRUE
J 0
(-6050 1275);
DISPLAY 0.872340 (-6050 1275);
DISPLAY INVISIBLE (-6050 1275);
FORCEPROP 1 LAST PATH I113
J 0
(-6377 1400);
DISPLAY 0.872340 (-6377 1400);
PAINT GREEN (-6377 1400);
DISPLAY INVISIBLE (-6377 1400);
FORCEADD TAP..1
(-6375 1600);
FORCEPROP 3 LASTPIN (-6425 1600) SIG_NAME P5E_CPU0_P1_TX_BUF_C_DP<11>
J 0
(-6415 1610);
DISPLAY 0.659574 (-6415 1610);
PAINT MONO (-6415 1610);
DISPLAY INVISIBLE (-6415 1610);
FORCEPROP 1 LASTPIN (-6425 1600) BN 11
J 0
(-6437 1608);
DISPLAY 0.680851 (-6437 1608);
PAINT GREEN (-6437 1608);
FORCEPROP 2 LAST CDS_LIB standard
J 0
(-6375 1600);
DISPLAY INVISIBLE (-6375 1600);
FORCEPROP 1 LAST BODY_TYPE PLUMBING
J 0
(-6375 1650);
DISPLAY 0.872340 (-6375 1650);
PAINT GREEN (-6375 1650);
DISPLAY INVISIBLE (-6375 1650);
FORCEPROP 1 LAST HDL_TAP TRUE
J 0
(-6050 1475);
DISPLAY 0.872340 (-6050 1475);
DISPLAY INVISIBLE (-6050 1475);
FORCEPROP 1 LAST PATH I114
J 0
(-6377 1600);
DISPLAY 0.872340 (-6377 1600);
PAINT GREEN (-6377 1600);
DISPLAY INVISIBLE (-6377 1600);
FORCEADD TAP..1
(-6375 1800);
FORCEPROP 3 LASTPIN (-6425 1800) SIG_NAME P5E_CPU0_P1_TX_BUF_C_DP<10>
J 0
(-6415 1810);
DISPLAY 0.659574 (-6415 1810);
PAINT MONO (-6415 1810);
DISPLAY INVISIBLE (-6415 1810);
FORCEPROP 1 LASTPIN (-6425 1800) BN 10
J 0
(-6437 1808);
DISPLAY 0.680851 (-6437 1808);
PAINT GREEN (-6437 1808);
FORCEPROP 2 LAST CDS_LIB standard
J 0
(-6375 1800);
DISPLAY INVISIBLE (-6375 1800);
FORCEPROP 1 LAST BODY_TYPE PLUMBING
J 0
(-6375 1850);
DISPLAY 0.872340 (-6375 1850);
PAINT GREEN (-6375 1850);
DISPLAY INVISIBLE (-6375 1850);
FORCEPROP 1 LAST HDL_TAP TRUE
J 0
(-6050 1675);
DISPLAY 0.872340 (-6050 1675);
DISPLAY INVISIBLE (-6050 1675);
FORCEPROP 1 LAST PATH I115
J 0
(-6377 1800);
DISPLAY 0.872340 (-6377 1800);
PAINT GREEN (-6377 1800);
DISPLAY INVISIBLE (-6377 1800);
FORCEADD TAP..1
(-6175 1550);
FORCEPROP 3 LASTPIN (-6225 1550) SIG_NAME P5E_CPU0_P1_TX_BUF_C_DN<11>
J 0
(-6215 1560);
DISPLAY 0.659574 (-6215 1560);
PAINT MONO (-6215 1560);
DISPLAY INVISIBLE (-6215 1560);
FORCEPROP 1 LASTPIN (-6225 1550) BN 11
J 0
(-6237 1558);
DISPLAY 0.680851 (-6237 1558);
PAINT GREEN (-6237 1558);
FORCEPROP 2 LAST CDS_LIB standard
J 0
(-6175 1550);
DISPLAY INVISIBLE (-6175 1550);
FORCEPROP 1 LAST BODY_TYPE PLUMBING
J 0
(-6175 1600);
DISPLAY 0.872340 (-6175 1600);
PAINT GREEN (-6175 1600);
DISPLAY INVISIBLE (-6175 1600);
FORCEPROP 1 LAST HDL_TAP TRUE
J 0
(-5850 1425);
DISPLAY 0.872340 (-5850 1425);
DISPLAY INVISIBLE (-5850 1425);
FORCEPROP 1 LAST PATH I116
J 0
(-6177 1550);
DISPLAY 0.872340 (-6177 1550);
PAINT GREEN (-6177 1550);
DISPLAY INVISIBLE (-6177 1550);
FORCEADD TAP..1
(-6175 1750);
FORCEPROP 3 LASTPIN (-6225 1750) SIG_NAME P5E_CPU0_P1_TX_BUF_C_DN<10>
J 0
(-6215 1760);
DISPLAY 0.659574 (-6215 1760);
PAINT MONO (-6215 1760);
DISPLAY INVISIBLE (-6215 1760);
FORCEPROP 1 LASTPIN (-6225 1750) BN 10
J 0
(-6237 1758);
DISPLAY 0.680851 (-6237 1758);
PAINT GREEN (-6237 1758);
FORCEPROP 2 LAST CDS_LIB standard
J 0
(-6175 1750);
DISPLAY INVISIBLE (-6175 1750);
FORCEPROP 1 LAST BODY_TYPE PLUMBING
J 0
(-6175 1800);
DISPLAY 0.872340 (-6175 1800);
PAINT GREEN (-6175 1800);
DISPLAY INVISIBLE (-6175 1800);
FORCEPROP 1 LAST HDL_TAP TRUE
J 0
(-5850 1625);
DISPLAY 0.872340 (-5850 1625);
DISPLAY INVISIBLE (-5850 1625);
FORCEPROP 1 LAST PATH I117
J 0
(-6177 1750);
DISPLAY 0.872340 (-6177 1750);
PAINT GREEN (-6177 1750);
DISPLAY INVISIBLE (-6177 1750);
FORCEADD TAP..1
(-6375 2000);
FORCEPROP 3 LASTPIN (-6425 2000) SIG_NAME P5E_CPU0_P1_TX_BUF_C_DP<9>
J 0
(-6415 2010);
DISPLAY 0.659574 (-6415 2010);
PAINT MONO (-6415 2010);
DISPLAY INVISIBLE (-6415 2010);
FORCEPROP 1 LASTPIN (-6425 2000) BN 9
J 0
(-6437 2008);
DISPLAY 0.680851 (-6437 2008);
PAINT GREEN (-6437 2008);
FORCEPROP 2 LAST CDS_LIB standard
J 0
(-6375 2000);
DISPLAY INVISIBLE (-6375 2000);
FORCEPROP 1 LAST BODY_TYPE PLUMBING
J 0
(-6375 2050);
DISPLAY 0.872340 (-6375 2050);
PAINT GREEN (-6375 2050);
DISPLAY INVISIBLE (-6375 2050);
FORCEPROP 1 LAST HDL_TAP TRUE
J 0
(-6050 1875);
DISPLAY 0.872340 (-6050 1875);
DISPLAY INVISIBLE (-6050 1875);
FORCEPROP 1 LAST PATH I118
J 0
(-6377 2000);
DISPLAY 0.872340 (-6377 2000);
PAINT GREEN (-6377 2000);
DISPLAY INVISIBLE (-6377 2000);
FORCEADD TAP..1
(-6375 2200);
FORCEPROP 3 LASTPIN (-6425 2200) SIG_NAME P5E_CPU0_P1_TX_BUF_C_DP<8>
J 0
(-6415 2210);
DISPLAY 0.659574 (-6415 2210);
PAINT MONO (-6415 2210);
DISPLAY INVISIBLE (-6415 2210);
FORCEPROP 1 LASTPIN (-6425 2200) BN 8
J 0
(-6437 2208);
DISPLAY 0.680851 (-6437 2208);
PAINT GREEN (-6437 2208);
FORCEPROP 2 LAST CDS_LIB standard
J 0
(-6375 2200);
DISPLAY INVISIBLE (-6375 2200);
FORCEPROP 1 LAST BODY_TYPE PLUMBING
J 0
(-6375 2250);
DISPLAY 0.872340 (-6375 2250);
PAINT GREEN (-6375 2250);
DISPLAY INVISIBLE (-6375 2250);
FORCEPROP 1 LAST HDL_TAP TRUE
J 0
(-6050 2075);
DISPLAY 0.872340 (-6050 2075);
DISPLAY INVISIBLE (-6050 2075);
FORCEPROP 1 LAST PATH I119
J 0
(-6377 2200);
DISPLAY 0.872340 (-6377 2200);
PAINT GREEN (-6377 2200);
DISPLAY INVISIBLE (-6377 2200);
FORCEADD TAP..1
R 2
(-3125 1400);
FORCEPROP 3 LASTPIN (-3075 1400) SIG_NAME P5E_CPU0_P1_TX_BUF_DP<4>
J 0
(-3065 1410);
DISPLAY 0.659574 (-3065 1410);
PAINT MONO (-3065 1410);
DISPLAY INVISIBLE (-3065 1410);
FORCEPROP 1 LASTPIN (-3075 1400) BN 4
J 2
(-3063 1408);
DISPLAY 0.680851 (-3063 1408);
PAINT GREEN (-3063 1408);
FORCEPROP 2 LAST CDS_LIB standard
J 0
(-3125 1400);
DISPLAY INVISIBLE (-3125 1400);
FORCEPROP 1 LAST BODY_TYPE PLUMBING
J 2
(-3125 1450);
DISPLAY 0.872340 (-3125 1450);
PAINT GREEN (-3125 1450);
DISPLAY INVISIBLE (-3125 1450);
FORCEPROP 1 LAST HDL_TAP TRUE
J 2
(-3450 1275);
DISPLAY 0.872340 (-3450 1275);
DISPLAY INVISIBLE (-3450 1275);
FORCEPROP 1 LAST PATH I12
J 2
(-3123 1400);
DISPLAY 0.872340 (-3123 1400);
PAINT GREEN (-3123 1400);
DISPLAY INVISIBLE (-3123 1400);
FORCEADD TAP..1
(-6175 1950);
FORCEPROP 3 LASTPIN (-6225 1950) SIG_NAME P5E_CPU0_P1_TX_BUF_C_DN<9>
J 0
(-6215 1960);
DISPLAY 0.659574 (-6215 1960);
PAINT MONO (-6215 1960);
DISPLAY INVISIBLE (-6215 1960);
FORCEPROP 1 LASTPIN (-6225 1950) BN 9
J 0
(-6237 1958);
DISPLAY 0.680851 (-6237 1958);
PAINT GREEN (-6237 1958);
FORCEPROP 2 LAST CDS_LIB standard
J 0
(-6175 1950);
DISPLAY INVISIBLE (-6175 1950);
FORCEPROP 1 LAST BODY_TYPE PLUMBING
J 0
(-6175 2000);
DISPLAY 0.872340 (-6175 2000);
PAINT GREEN (-6175 2000);
DISPLAY INVISIBLE (-6175 2000);
FORCEPROP 1 LAST HDL_TAP TRUE
J 0
(-5850 1825);
DISPLAY 0.872340 (-5850 1825);
DISPLAY INVISIBLE (-5850 1825);
FORCEPROP 1 LAST PATH I120
J 0
(-6177 1950);
DISPLAY 0.872340 (-6177 1950);
PAINT GREEN (-6177 1950);
DISPLAY INVISIBLE (-6177 1950);
FORCEADD TAP..1
(-6175 2150);
FORCEPROP 3 LASTPIN (-6225 2150) SIG_NAME P5E_CPU0_P1_TX_BUF_C_DN<8>
J 0
(-6215 2160);
DISPLAY 0.659574 (-6215 2160);
PAINT MONO (-6215 2160);
DISPLAY INVISIBLE (-6215 2160);
FORCEPROP 1 LASTPIN (-6225 2150) BN 8
J 0
(-6237 2158);
DISPLAY 0.680851 (-6237 2158);
PAINT GREEN (-6237 2158);
FORCEPROP 2 LAST CDS_LIB standard
J 0
(-6175 2150);
DISPLAY INVISIBLE (-6175 2150);
FORCEPROP 1 LAST BODY_TYPE PLUMBING
J 0
(-6175 2200);
DISPLAY 0.872340 (-6175 2200);
PAINT GREEN (-6175 2200);
DISPLAY INVISIBLE (-6175 2200);
FORCEPROP 1 LAST HDL_TAP TRUE
J 0
(-5850 2025);
DISPLAY 0.872340 (-5850 2025);
DISPLAY INVISIBLE (-5850 2025);
FORCEPROP 1 LAST PATH I121
J 0
(-6177 2150);
DISPLAY 0.872340 (-6177 2150);
PAINT GREEN (-6177 2150);
DISPLAY INVISIBLE (-6177 2150);
FORCEADD TAP..1
(-1875 3350);
FORCEPROP 3 LASTPIN (-1925 3350) SIG_NAME P5E_CPU0_P1_TX_BUF_DP<0>
J 0
(-1915 3360);
DISPLAY 0.659574 (-1915 3360);
PAINT MONO (-1915 3360);
DISPLAY INVISIBLE (-1915 3360);
FORCEPROP 1 LASTPIN (-1925 3350) BN 0
J 0
(-1937 3358);
DISPLAY 0.680851 (-1937 3358);
PAINT GREEN (-1937 3358);
FORCEPROP 2 LAST CDS_LIB standard
J 0
(-1875 3350);
DISPLAY INVISIBLE (-1875 3350);
FORCEPROP 1 LAST BODY_TYPE PLUMBING
J 0
(-1875 3400);
DISPLAY 0.872340 (-1875 3400);
PAINT GREEN (-1875 3400);
DISPLAY INVISIBLE (-1875 3400);
FORCEPROP 1 LAST HDL_TAP TRUE
J 0
(-1550 3225);
DISPLAY 0.872340 (-1550 3225);
DISPLAY INVISIBLE (-1550 3225);
FORCEPROP 1 LAST PATH I122
J 0
(-1877 3350);
DISPLAY 0.872340 (-1877 3350);
PAINT GREEN (-1877 3350);
DISPLAY INVISIBLE (-1877 3350);
FORCEADD TAP..1
(-1675 3250);
FORCEPROP 3 LASTPIN (-1725 3250) SIG_NAME P5E_CPU0_P1_TX_BUF_DN<0>
J 0
(-1715 3260);
DISPLAY 0.659574 (-1715 3260);
PAINT MONO (-1715 3260);
DISPLAY INVISIBLE (-1715 3260);
FORCEPROP 1 LASTPIN (-1725 3250) BN 0
J 0
(-1737 3258);
DISPLAY 0.680851 (-1737 3258);
PAINT GREEN (-1737 3258);
FORCEPROP 2 LAST CDS_LIB standard
J 0
(-1675 3250);
DISPLAY INVISIBLE (-1675 3250);
FORCEPROP 1 LAST BODY_TYPE PLUMBING
J 0
(-1675 3300);
DISPLAY 0.872340 (-1675 3300);
PAINT GREEN (-1675 3300);
DISPLAY INVISIBLE (-1675 3300);
FORCEPROP 1 LAST HDL_TAP TRUE
J 0
(-1350 3125);
DISPLAY 0.872340 (-1350 3125);
DISPLAY INVISIBLE (-1350 3125);
FORCEPROP 1 LAST PATH I123
J 0
(-1677 3250);
DISPLAY 0.872340 (-1677 3250);
PAINT GREEN (-1677 3250);
DISPLAY INVISIBLE (-1677 3250);
FORCEADD TAP..1
(-1875 3700);
FORCEPROP 3 LASTPIN (-1925 3700) SIG_NAME P5E_CPU0_P1_TX_BUF_DP<1>
J 0
(-1915 3710);
DISPLAY 0.659574 (-1915 3710);
PAINT MONO (-1915 3710);
DISPLAY INVISIBLE (-1915 3710);
FORCEPROP 1 LASTPIN (-1925 3700) BN 1
J 0
(-1937 3708);
DISPLAY 0.680851 (-1937 3708);
PAINT GREEN (-1937 3708);
FORCEPROP 2 LAST CDS_LIB standard
J 0
(-1875 3700);
DISPLAY INVISIBLE (-1875 3700);
FORCEPROP 1 LAST BODY_TYPE PLUMBING
J 0
(-1875 3750);
DISPLAY 0.872340 (-1875 3750);
PAINT GREEN (-1875 3750);
DISPLAY INVISIBLE (-1875 3750);
FORCEPROP 1 LAST HDL_TAP TRUE
J 0
(-1550 3575);
DISPLAY 0.872340 (-1550 3575);
DISPLAY INVISIBLE (-1550 3575);
FORCEPROP 1 LAST PATH I124
J 0
(-1877 3700);
DISPLAY 0.872340 (-1877 3700);
PAINT GREEN (-1877 3700);
DISPLAY INVISIBLE (-1877 3700);
FORCEADD TAP..1
(-1675 3600);
FORCEPROP 3 LASTPIN (-1725 3600) SIG_NAME P5E_CPU0_P1_TX_BUF_DN<1>
J 0
(-1715 3610);
DISPLAY 0.659574 (-1715 3610);
PAINT MONO (-1715 3610);
DISPLAY INVISIBLE (-1715 3610);
FORCEPROP 1 LASTPIN (-1725 3600) BN 1
J 0
(-1737 3608);
DISPLAY 0.680851 (-1737 3608);
PAINT GREEN (-1737 3608);
FORCEPROP 2 LAST CDS_LIB standard
J 0
(-1675 3600);
DISPLAY INVISIBLE (-1675 3600);
FORCEPROP 1 LAST BODY_TYPE PLUMBING
J 0
(-1675 3650);
DISPLAY 0.872340 (-1675 3650);
PAINT GREEN (-1675 3650);
DISPLAY INVISIBLE (-1675 3650);
FORCEPROP 1 LAST HDL_TAP TRUE
J 0
(-1350 3475);
DISPLAY 0.872340 (-1350 3475);
DISPLAY INVISIBLE (-1350 3475);
FORCEPROP 1 LAST PATH I125
J 0
(-1677 3600);
DISPLAY 0.872340 (-1677 3600);
PAINT GREEN (-1677 3600);
DISPLAY INVISIBLE (-1677 3600);
FORCEADD OFFPAGE..2
(-5175 2175);
FORCEPROP 2 LAST $XR0 117 
J 0
(-4986 2175);
DISPLAY 0.638298 (-4986 2175);
PAINT MONO (-4986 2175);
FORCEPROP 2 LAST CDS_LIB standard
J 0
(-5175 2175);
DISPLAY INVISIBLE (-5175 2175);
FORCEPROP 1 LAST OFFPAGE TRUE
J 0
(-4850 2050);
DISPLAY 0.872340 (-4850 2050);
DISPLAY INVISIBLE (-4850 2050);
FORCEPROP 1 LAST COMMENT_BODY TRUE
J 0
(-5220 2080);
DISPLAY 0.872340 (-5220 2080);
PAINT GREEN (-5220 2080);
DISPLAY INVISIBLE (-5220 2080);
FORCEPROP 2 LAST PATH I126
J 0
(-4975 2225);
DISPLAY 0.680851 (-4975 2225);
DISPLAY INVISIBLE (-4975 2225);
FORCEADD OFFPAGE..2
(-5175 2225);
FORCEPROP 2 LAST $XR0 117 
J 0
(-4986 2225);
DISPLAY 0.638298 (-4986 2225);
PAINT MONO (-4986 2225);
FORCEPROP 2 LAST CDS_LIB standard
J 0
(-5175 2225);
DISPLAY INVISIBLE (-5175 2225);
FORCEPROP 1 LAST OFFPAGE TRUE
J 0
(-4850 2100);
DISPLAY 0.872340 (-4850 2100);
DISPLAY INVISIBLE (-4850 2100);
FORCEPROP 1 LAST COMMENT_BODY TRUE
J 0
(-5220 2130);
DISPLAY 0.872340 (-5220 2130);
PAINT GREEN (-5220 2130);
DISPLAY INVISIBLE (-5220 2130);
FORCEPROP 2 LAST PATH I127
J 0
(-4975 2275);
DISPLAY 0.680851 (-4975 2275);
DISPLAY INVISIBLE (-4975 2275);
FORCEADD TAP..1
(-1875 4050);
FORCEPROP 3 LASTPIN (-1925 4050) SIG_NAME P5E_CPU0_P1_TX_BUF_DP<2>
J 0
(-1915 4060);
DISPLAY 0.659574 (-1915 4060);
PAINT MONO (-1915 4060);
DISPLAY INVISIBLE (-1915 4060);
FORCEPROP 1 LASTPIN (-1925 4050) BN 2
J 0
(-1937 4058);
DISPLAY 0.680851 (-1937 4058);
PAINT GREEN (-1937 4058);
FORCEPROP 2 LAST CDS_LIB standard
J 0
(-1875 4050);
DISPLAY INVISIBLE (-1875 4050);
FORCEPROP 1 LAST BODY_TYPE PLUMBING
J 0
(-1875 4100);
DISPLAY 0.872340 (-1875 4100);
PAINT GREEN (-1875 4100);
DISPLAY INVISIBLE (-1875 4100);
FORCEPROP 1 LAST HDL_TAP TRUE
J 0
(-1550 3925);
DISPLAY 0.872340 (-1550 3925);
DISPLAY INVISIBLE (-1550 3925);
FORCEPROP 1 LAST PATH I128
J 0
(-1877 4050);
DISPLAY 0.872340 (-1877 4050);
PAINT GREEN (-1877 4050);
DISPLAY INVISIBLE (-1877 4050);
FORCEADD TAP..1
(-1675 3950);
FORCEPROP 3 LASTPIN (-1725 3950) SIG_NAME P5E_CPU0_P1_TX_BUF_DN<2>
J 0
(-1715 3960);
DISPLAY 0.659574 (-1715 3960);
PAINT MONO (-1715 3960);
DISPLAY INVISIBLE (-1715 3960);
FORCEPROP 1 LASTPIN (-1725 3950) BN 2
J 0
(-1737 3958);
DISPLAY 0.680851 (-1737 3958);
PAINT GREEN (-1737 3958);
FORCEPROP 2 LAST CDS_LIB standard
J 0
(-1675 3950);
DISPLAY INVISIBLE (-1675 3950);
FORCEPROP 1 LAST BODY_TYPE PLUMBING
J 0
(-1675 4000);
DISPLAY 0.872340 (-1675 4000);
PAINT GREEN (-1675 4000);
DISPLAY INVISIBLE (-1675 4000);
FORCEPROP 1 LAST HDL_TAP TRUE
J 0
(-1350 3825);
DISPLAY 0.872340 (-1350 3825);
DISPLAY INVISIBLE (-1350 3825);
FORCEPROP 1 LAST PATH I129
J 0
(-1677 3950);
DISPLAY 0.872340 (-1677 3950);
PAINT GREEN (-1677 3950);
DISPLAY INVISIBLE (-1677 3950);
FORCEADD TAP..1
R 2
(-3125 1600);
FORCEPROP 3 LASTPIN (-3075 1600) SIG_NAME P5E_CPU0_P1_TX_BUF_DP<3>
J 0
(-3065 1610);
DISPLAY 0.659574 (-3065 1610);
PAINT MONO (-3065 1610);
DISPLAY INVISIBLE (-3065 1610);
FORCEPROP 1 LASTPIN (-3075 1600) BN 3
J 2
(-3063 1608);
DISPLAY 0.680851 (-3063 1608);
PAINT GREEN (-3063 1608);
FORCEPROP 2 LAST CDS_LIB standard
J 0
(-3125 1600);
DISPLAY INVISIBLE (-3125 1600);
FORCEPROP 1 LAST BODY_TYPE PLUMBING
J 2
(-3125 1650);
DISPLAY 0.872340 (-3125 1650);
PAINT GREEN (-3125 1650);
DISPLAY INVISIBLE (-3125 1650);
FORCEPROP 1 LAST HDL_TAP TRUE
J 2
(-3450 1475);
DISPLAY 0.872340 (-3450 1475);
DISPLAY INVISIBLE (-3450 1475);
FORCEPROP 1 LAST PATH I13
J 2
(-3123 1600);
DISPLAY 0.872340 (-3123 1600);
PAINT GREEN (-3123 1600);
DISPLAY INVISIBLE (-3123 1600);
FORCEADD TAP..1
(-1675 4300);
FORCEPROP 3 LASTPIN (-1725 4300) SIG_NAME P5E_CPU0_P1_TX_BUF_DN<3>
J 0
(-1715 4310);
DISPLAY 0.659574 (-1715 4310);
PAINT MONO (-1715 4310);
DISPLAY INVISIBLE (-1715 4310);
FORCEPROP 1 LASTPIN (-1725 4300) BN 3
J 0
(-1737 4308);
DISPLAY 0.680851 (-1737 4308);
PAINT GREEN (-1737 4308);
FORCEPROP 2 LAST CDS_LIB standard
J 0
(-1675 4300);
DISPLAY INVISIBLE (-1675 4300);
FORCEPROP 1 LAST BODY_TYPE PLUMBING
J 0
(-1675 4350);
DISPLAY 0.872340 (-1675 4350);
PAINT GREEN (-1675 4350);
DISPLAY INVISIBLE (-1675 4350);
FORCEPROP 1 LAST HDL_TAP TRUE
J 0
(-1350 4175);
DISPLAY 0.872340 (-1350 4175);
DISPLAY INVISIBLE (-1350 4175);
FORCEPROP 1 LAST PATH I130
J 0
(-1677 4300);
DISPLAY 0.872340 (-1677 4300);
PAINT GREEN (-1677 4300);
DISPLAY INVISIBLE (-1677 4300);
FORCEADD TAP..1
(-1875 4400);
FORCEPROP 3 LASTPIN (-1925 4400) SIG_NAME P5E_CPU0_P1_TX_BUF_DP<3>
J 0
(-1915 4410);
DISPLAY 0.659574 (-1915 4410);
PAINT MONO (-1915 4410);
DISPLAY INVISIBLE (-1915 4410);
FORCEPROP 1 LASTPIN (-1925 4400) BN 3
J 0
(-1937 4408);
DISPLAY 0.680851 (-1937 4408);
PAINT GREEN (-1937 4408);
FORCEPROP 2 LAST CDS_LIB standard
J 0
(-1875 4400);
DISPLAY INVISIBLE (-1875 4400);
FORCEPROP 1 LAST BODY_TYPE PLUMBING
J 0
(-1875 4450);
DISPLAY 0.872340 (-1875 4450);
PAINT GREEN (-1875 4450);
DISPLAY INVISIBLE (-1875 4450);
FORCEPROP 1 LAST HDL_TAP TRUE
J 0
(-1550 4275);
DISPLAY 0.872340 (-1550 4275);
DISPLAY INVISIBLE (-1550 4275);
FORCEPROP 1 LAST PATH I131
J 0
(-1877 4400);
DISPLAY 0.872340 (-1877 4400);
PAINT GREEN (-1877 4400);
DISPLAY INVISIBLE (-1877 4400);
FORCEADD TAP..1
(-1875 4750);
FORCEPROP 3 LASTPIN (-1925 4750) SIG_NAME P5E_CPU0_P1_TX_BUF_DP<4>
J 0
(-1915 4760);
DISPLAY 0.659574 (-1915 4760);
PAINT MONO (-1915 4760);
DISPLAY INVISIBLE (-1915 4760);
FORCEPROP 1 LASTPIN (-1925 4750) BN 4
J 0
(-1937 4758);
DISPLAY 0.680851 (-1937 4758);
PAINT GREEN (-1937 4758);
FORCEPROP 2 LAST CDS_LIB standard
J 0
(-1875 4750);
DISPLAY INVISIBLE (-1875 4750);
FORCEPROP 1 LAST BODY_TYPE PLUMBING
J 0
(-1875 4800);
DISPLAY 0.872340 (-1875 4800);
PAINT GREEN (-1875 4800);
DISPLAY INVISIBLE (-1875 4800);
FORCEPROP 1 LAST HDL_TAP TRUE
J 0
(-1550 4625);
DISPLAY 0.872340 (-1550 4625);
DISPLAY INVISIBLE (-1550 4625);
FORCEPROP 1 LAST PATH I132
J 0
(-1877 4750);
DISPLAY 0.872340 (-1877 4750);
PAINT GREEN (-1877 4750);
DISPLAY INVISIBLE (-1877 4750);
FORCEADD TAP..1
(-1675 4650);
FORCEPROP 3 LASTPIN (-1725 4650) SIG_NAME P5E_CPU0_P1_TX_BUF_DN<4>
J 0
(-1715 4660);
DISPLAY 0.659574 (-1715 4660);
PAINT MONO (-1715 4660);
DISPLAY INVISIBLE (-1715 4660);
FORCEPROP 1 LASTPIN (-1725 4650) BN 4
J 0
(-1737 4658);
DISPLAY 0.680851 (-1737 4658);
PAINT GREEN (-1737 4658);
FORCEPROP 2 LAST CDS_LIB standard
J 0
(-1675 4650);
DISPLAY INVISIBLE (-1675 4650);
FORCEPROP 1 LAST BODY_TYPE PLUMBING
J 0
(-1675 4700);
DISPLAY 0.872340 (-1675 4700);
PAINT GREEN (-1675 4700);
DISPLAY INVISIBLE (-1675 4700);
FORCEPROP 1 LAST HDL_TAP TRUE
J 0
(-1350 4525);
DISPLAY 0.872340 (-1350 4525);
DISPLAY INVISIBLE (-1350 4525);
FORCEPROP 1 LAST PATH I133
J 0
(-1677 4650);
DISPLAY 0.872340 (-1677 4650);
PAINT GREEN (-1677 4650);
DISPLAY INVISIBLE (-1677 4650);
FORCEADD TAP..1
(-1875 5100);
FORCEPROP 3 LASTPIN (-1925 5100) SIG_NAME P5E_CPU0_P1_TX_BUF_DP<5>
J 0
(-1915 5110);
DISPLAY 0.659574 (-1915 5110);
PAINT MONO (-1915 5110);
DISPLAY INVISIBLE (-1915 5110);
FORCEPROP 1 LASTPIN (-1925 5100) BN 5
J 0
(-1937 5108);
DISPLAY 0.680851 (-1937 5108);
PAINT GREEN (-1937 5108);
FORCEPROP 2 LAST CDS_LIB standard
J 0
(-1875 5100);
DISPLAY INVISIBLE (-1875 5100);
FORCEPROP 1 LAST BODY_TYPE PLUMBING
J 0
(-1875 5150);
DISPLAY 0.872340 (-1875 5150);
PAINT GREEN (-1875 5150);
DISPLAY INVISIBLE (-1875 5150);
FORCEPROP 1 LAST HDL_TAP TRUE
J 0
(-1550 4975);
DISPLAY 0.872340 (-1550 4975);
DISPLAY INVISIBLE (-1550 4975);
FORCEPROP 1 LAST PATH I134
J 0
(-1877 5100);
DISPLAY 0.872340 (-1877 5100);
PAINT GREEN (-1877 5100);
DISPLAY INVISIBLE (-1877 5100);
FORCEADD TAP..1
(-1675 5000);
FORCEPROP 3 LASTPIN (-1725 5000) SIG_NAME P5E_CPU0_P1_TX_BUF_DN<5>
J 0
(-1715 5010);
DISPLAY 0.659574 (-1715 5010);
PAINT MONO (-1715 5010);
DISPLAY INVISIBLE (-1715 5010);
FORCEPROP 1 LASTPIN (-1725 5000) BN 5
J 0
(-1737 5008);
DISPLAY 0.680851 (-1737 5008);
PAINT GREEN (-1737 5008);
FORCEPROP 2 LAST CDS_LIB standard
J 0
(-1675 5000);
DISPLAY INVISIBLE (-1675 5000);
FORCEPROP 1 LAST BODY_TYPE PLUMBING
J 0
(-1675 5050);
DISPLAY 0.872340 (-1675 5050);
PAINT GREEN (-1675 5050);
DISPLAY INVISIBLE (-1675 5050);
FORCEPROP 1 LAST HDL_TAP TRUE
J 0
(-1350 4875);
DISPLAY 0.872340 (-1350 4875);
DISPLAY INVISIBLE (-1350 4875);
FORCEPROP 1 LAST PATH I135
J 0
(-1677 5000);
DISPLAY 0.872340 (-1677 5000);
PAINT GREEN (-1677 5000);
DISPLAY INVISIBLE (-1677 5000);
FORCEADD TAP..1
(-1675 5350);
FORCEPROP 3 LASTPIN (-1725 5350) SIG_NAME P5E_CPU0_P1_TX_BUF_DN<6>
J 0
(-1715 5360);
DISPLAY 0.659574 (-1715 5360);
PAINT MONO (-1715 5360);
DISPLAY INVISIBLE (-1715 5360);
FORCEPROP 1 LASTPIN (-1725 5350) BN 6
J 0
(-1737 5358);
DISPLAY 0.680851 (-1737 5358);
PAINT GREEN (-1737 5358);
FORCEPROP 2 LAST CDS_LIB standard
J 0
(-1675 5350);
DISPLAY INVISIBLE (-1675 5350);
FORCEPROP 1 LAST BODY_TYPE PLUMBING
J 0
(-1675 5400);
DISPLAY 0.872340 (-1675 5400);
PAINT GREEN (-1675 5400);
DISPLAY INVISIBLE (-1675 5400);
FORCEPROP 1 LAST HDL_TAP TRUE
J 0
(-1350 5225);
DISPLAY 0.872340 (-1350 5225);
DISPLAY INVISIBLE (-1350 5225);
FORCEPROP 1 LAST PATH I136
J 0
(-1677 5350);
DISPLAY 0.872340 (-1677 5350);
PAINT GREEN (-1677 5350);
DISPLAY INVISIBLE (-1677 5350);
FORCEADD TAP..1
(-1875 5450);
FORCEPROP 3 LASTPIN (-1925 5450) SIG_NAME P5E_CPU0_P1_TX_BUF_DP<6>
J 0
(-1915 5460);
DISPLAY 0.659574 (-1915 5460);
PAINT MONO (-1915 5460);
DISPLAY INVISIBLE (-1915 5460);
FORCEPROP 1 LASTPIN (-1925 5450) BN 6
J 0
(-1937 5458);
DISPLAY 0.680851 (-1937 5458);
PAINT GREEN (-1937 5458);
FORCEPROP 2 LAST CDS_LIB standard
J 0
(-1875 5450);
DISPLAY INVISIBLE (-1875 5450);
FORCEPROP 1 LAST BODY_TYPE PLUMBING
J 0
(-1875 5500);
DISPLAY 0.872340 (-1875 5500);
PAINT GREEN (-1875 5500);
DISPLAY INVISIBLE (-1875 5500);
FORCEPROP 1 LAST HDL_TAP TRUE
J 0
(-1550 5325);
DISPLAY 0.872340 (-1550 5325);
DISPLAY INVISIBLE (-1550 5325);
FORCEPROP 1 LAST PATH I137
J 0
(-1877 5450);
DISPLAY 0.872340 (-1877 5450);
PAINT GREEN (-1877 5450);
DISPLAY INVISIBLE (-1877 5450);
FORCEADD TAP..1
(-1875 5800);
FORCEPROP 3 LASTPIN (-1925 5800) SIG_NAME P5E_CPU0_P1_TX_BUF_DP<7>
J 0
(-1915 5810);
DISPLAY 0.659574 (-1915 5810);
PAINT MONO (-1915 5810);
DISPLAY INVISIBLE (-1915 5810);
FORCEPROP 1 LASTPIN (-1925 5800) BN 7
J 0
(-1937 5808);
DISPLAY 0.680851 (-1937 5808);
PAINT GREEN (-1937 5808);
FORCEPROP 2 LAST CDS_LIB standard
J 0
(-1875 5800);
DISPLAY INVISIBLE (-1875 5800);
FORCEPROP 1 LAST BODY_TYPE PLUMBING
J 0
(-1875 5850);
DISPLAY 0.872340 (-1875 5850);
PAINT GREEN (-1875 5850);
DISPLAY INVISIBLE (-1875 5850);
FORCEPROP 1 LAST HDL_TAP TRUE
J 0
(-1550 5675);
DISPLAY 0.872340 (-1550 5675);
DISPLAY INVISIBLE (-1550 5675);
FORCEPROP 1 LAST PATH I138
J 0
(-1877 5800);
DISPLAY 0.872340 (-1877 5800);
PAINT GREEN (-1877 5800);
DISPLAY INVISIBLE (-1877 5800);
FORCEADD TAP..1
(-1675 5700);
FORCEPROP 3 LASTPIN (-1725 5700) SIG_NAME P5E_CPU0_P1_TX_BUF_DN<7>
J 0
(-1715 5710);
DISPLAY 0.659574 (-1715 5710);
PAINT MONO (-1715 5710);
DISPLAY INVISIBLE (-1715 5710);
FORCEPROP 1 LASTPIN (-1725 5700) BN 7
J 0
(-1737 5708);
DISPLAY 0.680851 (-1737 5708);
PAINT GREEN (-1737 5708);
FORCEPROP 2 LAST CDS_LIB standard
J 0
(-1675 5700);
DISPLAY INVISIBLE (-1675 5700);
FORCEPROP 1 LAST BODY_TYPE PLUMBING
J 0
(-1675 5750);
DISPLAY 0.872340 (-1675 5750);
PAINT GREEN (-1675 5750);
DISPLAY INVISIBLE (-1675 5750);
FORCEPROP 1 LAST HDL_TAP TRUE
J 0
(-1350 5575);
DISPLAY 0.872340 (-1350 5575);
DISPLAY INVISIBLE (-1350 5575);
FORCEPROP 1 LAST PATH I139
J 0
(-1677 5700);
DISPLAY 0.872340 (-1677 5700);
PAINT GREEN (-1677 5700);
DISPLAY INVISIBLE (-1677 5700);
FORCEADD TAP..1
R 2
(-3125 1800);
FORCEPROP 3 LASTPIN (-3075 1800) SIG_NAME P5E_CPU0_P1_TX_BUF_DP<2>
J 0
(-3065 1810);
DISPLAY 0.659574 (-3065 1810);
PAINT MONO (-3065 1810);
DISPLAY INVISIBLE (-3065 1810);
FORCEPROP 1 LASTPIN (-3075 1800) BN 2
J 2
(-3063 1808);
DISPLAY 0.680851 (-3063 1808);
PAINT GREEN (-3063 1808);
FORCEPROP 2 LAST CDS_LIB standard
J 0
(-3125 1800);
DISPLAY INVISIBLE (-3125 1800);
FORCEPROP 1 LAST BODY_TYPE PLUMBING
J 2
(-3125 1850);
DISPLAY 0.872340 (-3125 1850);
PAINT GREEN (-3125 1850);
DISPLAY INVISIBLE (-3125 1850);
FORCEPROP 1 LAST HDL_TAP TRUE
J 2
(-3450 1675);
DISPLAY 0.872340 (-3450 1675);
DISPLAY INVISIBLE (-3450 1675);
FORCEPROP 1 LAST PATH I14
J 2
(-3123 1800);
DISPLAY 0.872340 (-3123 1800);
PAINT GREEN (-3123 1800);
DISPLAY INVISIBLE (-3123 1800);
FORCEADD OFFPAGE..5
R 2
(-700 5725);
FORCEPROP 2 LAST $XR0 287 
J 0
(-511 5725);
DISPLAY 0.638298 (-511 5725);
PAINT MONO (-511 5725);
FORCEPROP 2 LAST CDS_LIB standard
J 0
(-700 5725);
DISPLAY INVISIBLE (-700 5725);
FORCEPROP 1 LAST OFFPAGE TRUE
J 2
(-1025 5600);
DISPLAY 0.872340 (-1025 5600);
PAINT GREEN (-1025 5600);
DISPLAY INVISIBLE (-1025 5600);
FORCEPROP 1 LAST COMMENT_BODY TRUE
J 2
(-800 5650);
DISPLAY 0.872340 (-800 5650);
PAINT GREEN (-800 5650);
DISPLAY INVISIBLE (-800 5650);
FORCEPROP 2 LAST PATH I140
J 0
(-525 5800);
DISPLAY 0.680851 (-525 5800);
DISPLAY INVISIBLE (-525 5800);
FORCEADD OFFPAGE..5
R 2
(-675 5825);
FORCEPROP 2 LAST $XR0 287 
J 0
(-486 5825);
DISPLAY 0.638298 (-486 5825);
PAINT MONO (-486 5825);
FORCEPROP 2 LAST CDS_LIB standard
J 0
(-675 5825);
DISPLAY INVISIBLE (-675 5825);
FORCEPROP 1 LAST OFFPAGE TRUE
J 2
(-1000 5700);
DISPLAY 0.872340 (-1000 5700);
PAINT GREEN (-1000 5700);
DISPLAY INVISIBLE (-1000 5700);
FORCEPROP 1 LAST COMMENT_BODY TRUE
J 2
(-775 5750);
DISPLAY 0.872340 (-775 5750);
PAINT GREEN (-775 5750);
DISPLAY INVISIBLE (-775 5750);
FORCEPROP 2 LAST PATH I141
J 0
(-500 5900);
DISPLAY 0.680851 (-500 5900);
DISPLAY INVISIBLE (-500 5900);
FORCEADD PT5161LRS..11
(-2600 4550);
FORCEPROP 1 LAST LOCATION U6011
J 0
(-2950 6175);
DISPLAY 0.723404 (-2950 6175);
PAINT GREEN (-2950 6175);
FORCEPROP 0 LAST $SEC 11
J 0
(-2950 6325);
DISPLAY 0.680851 (-2950 6325);
PAINT MONO (-2950 6325);
DISPLAY INVISIBLE (-2950 6325);
FORCEPROP 0 LAST CDS_SEC 11
J 0
(-2950 6325);
DISPLAY 0.680851 (-2950 6325);
DISPLAY INVISIBLE (-2950 6325);
FORCEPROP 0 LASTPIN (-2150 5700) $PN CK10
J 0
(-2140 5710);
DISPLAY 0.680851 (-2140 5710);
PAINT MONO (-2140 5710);
FORCEPROP 0 LASTPIN (-2150 5350) $PN CU10
J 0
(-2140 5360);
DISPLAY 0.680851 (-2140 5360);
PAINT MONO (-2140 5360);
FORCEPROP 0 LASTPIN (-2150 5000) $PN DD10
J 0
(-2140 5010);
DISPLAY 0.680851 (-2140 5010);
PAINT MONO (-2140 5010);
FORCEPROP 0 LASTPIN (-2150 4650) $PN DL10
J 0
(-2140 4660);
DISPLAY 0.680851 (-2140 4660);
PAINT MONO (-2140 4660);
FORCEPROP 0 LASTPIN (-2150 4300) $PN DV10
J 0
(-2140 4310);
DISPLAY 0.680851 (-2140 4310);
PAINT MONO (-2140 4310);
FORCEPROP 0 LASTPIN (-2150 3950) $PN EE10
J 0
(-2140 3960);
DISPLAY 0.680851 (-2140 3960);
PAINT MONO (-2140 3960);
FORCEPROP 0 LASTPIN (-2150 3600) $PN EM10
J 0
(-2140 3610);
DISPLAY 0.680851 (-2140 3610);
PAINT MONO (-2140 3610);
FORCEPROP 0 LASTPIN (-2150 3250) $PN EW10
J 0
(-2140 3260);
DISPLAY 0.680851 (-2140 3260);
PAINT MONO (-2140 3260);
FORCEPROP 0 LASTPIN (-2150 5800) $PN CH7
J 0
(-2140 5810);
DISPLAY 0.680851 (-2140 5810);
PAINT MONO (-2140 5810);
FORCEPROP 0 LASTPIN (-2150 5450) $PN CR7
J 0
(-2140 5460);
DISPLAY 0.680851 (-2140 5460);
PAINT MONO (-2140 5460);
FORCEPROP 0 LASTPIN (-2150 5100) $PN DB7
J 0
(-2140 5110);
DISPLAY 0.680851 (-2140 5110);
PAINT MONO (-2140 5110);
FORCEPROP 0 LASTPIN (-2150 4750) $PN DJ7
J 0
(-2140 4760);
DISPLAY 0.680851 (-2140 4760);
PAINT MONO (-2140 4760);
FORCEPROP 0 LASTPIN (-2150 4400) $PN DT7
J 0
(-2140 4410);
DISPLAY 0.680851 (-2140 4410);
PAINT MONO (-2140 4410);
FORCEPROP 0 LASTPIN (-2150 4050) $PN EC7
J 0
(-2140 4060);
DISPLAY 0.680851 (-2140 4060);
PAINT MONO (-2140 4060);
FORCEPROP 0 LASTPIN (-2150 3700) $PN EK7
J 0
(-2140 3710);
DISPLAY 0.680851 (-2140 3710);
PAINT MONO (-2140 3710);
FORCEPROP 0 LASTPIN (-2150 3350) $PN EU7
J 0
(-2140 3360);
DISPLAY 0.680851 (-2140 3360);
PAINT MONO (-2140 3360);
FORCEPROP 1 LAST MATERIAL IC
J 0
(-2950 6025);
DISPLAY 0.723404 (-2950 6025);
PAINT GREEN (-2950 6025);
FORCEPROP 2 LAST VALUE PT5161LRS
J 0
(-2950 6225);
DISPLAY 0.680851 (-2950 6225);
FORCEPROP 2 LAST PART_TYPE SMLF
J 0
(-2950 6275);
DISPLAY 0.680851 (-2950 6275);
FORCEPROP 2 LAST CDS_LIB pure_quanta
J 0
(-2600 4550);
DISPLAY INVISIBLE (-2600 4550);
FORCEPROP 1 LAST CDS_LMAN_SYM_OUTLINE -350,1450,300,-1400
J 0
(-2600 4550);
DISPLAY 0.468085 (-2600 4550);
PAINT GREEN (-2600 4550);
DISPLAY INVISIBLE (-2600 4550);
FORCEPROP 1 LAST NEEDS_NO_SIZE TRUE
J 0
(-2600 4550);
DISPLAY 0.723404 (-2600 4550);
PAINT GREEN (-2600 4550);
DISPLAY INVISIBLE (-2600 4550);
FORCEPROP 1 LAST PATH I142
J 0
(-2600 4550);
DISPLAY 0.723404 (-2600 4550);
PAINT GREEN (-2600 4550);
DISPLAY INVISIBLE (-2600 4550);
FORCEPROP 1 LAST PART_NUMBER AJ051610U03
J 0
(-2950 6100);
DISPLAY 0.723404 (-2950 6100);
PAINT GREEN (-2950 6100);
DISPLAY INVISIBLE (-2950 6100);
FORCEADD Q_CAP_DIFFBUS..2
R 2
(-2400 750);
FORCEPROP 1 LAST LOCATION C6548
J 2
(-2125 750);
DISPLAY 0.723404 (-2125 750);
PAINT GREEN (-2125 750);
FORCEPROP 2 LAST $SEC 1
J 2
(-2225 825);
DISPLAY 0.680851 (-2225 825);
PAINT MONO (-2225 825);
DISPLAY INVISIBLE (-2225 825);
FORCEPROP 2 LAST CDS_SEC 1
J 2
(-2225 825);
DISPLAY 0.680851 (-2225 825);
DISPLAY INVISIBLE (-2225 825);
FORCEPROP 2 LASTPIN (-2325 750) $PN 1
J 0
(-2315 760);
DISPLAY 0.808511 (-2315 760);
FORCEPROP 2 LASTPIN (-2475 750) $PN 2
J 2
(-2485 760);
DISPLAY 0.808511 (-2485 760);
FORCEPROP 2 LAST VALUE DIFF BUS_0.22UF
J 2
(-2550 750);
DISPLAY 0.553191 (-2550 750);
FORCEPROP 1 LAST CDS_LMAN_SYM_OUTLINE -25,50,25,-50
J 2
(-2400 750);
DISPLAY 0.468085 (-2400 750);
PAINT GREEN (-2400 750);
DISPLAY INVISIBLE (-2400 750);
FORCEPROP 2 LAST CDS_LIB pure_quanta
J 2
(-2400 750);
DISPLAY INVISIBLE (-2400 750);
FORCEPROP 1 LAST PIN_NAMES_ROTATE TRUE
J 2
(-2400 750);
DISPLAY 0.489362 (-2400 750);
PAINT GREEN (-2400 750);
DISPLAY INVISIBLE (-2400 750);
FORCEPROP 2 LAST VOLTAGE 6.3V
J 2
(-2750 800);
DISPLAY 0.553191 (-2750 800);
DISPLAY INVISIBLE (-2750 800);
FORCEPROP 1 LAST MATERIAL X6S
J 2
(-2391 829);
DISPLAY 0.574468 (-2391 829);
PAINT GREEN (-2391 829);
DISPLAY INVISIBLE (-2391 829);
FORCEPROP 2 LAST PACK_TYPE C0201
J 2
(-2575 800);
DISPLAY 0.553191 (-2575 800);
DISPLAY INVISIBLE (-2575 800);
FORCEPROP 2 LAST TOLERANCE 20%
J 2
(-2475 800);
DISPLAY 0.553191 (-2475 800);
DISPLAY INVISIBLE (-2475 800);
FORCEPROP 1 LAST PATH I15
J 2
(-2400 750);
DISPLAY 0.723404 (-2400 750);
DISPLAY INVISIBLE (-2400 750);
FORCEPROP 1 LAST PART_NUMBER SP_CH4221MEE01
J 2
(-2516 838);
DISPLAY 0.574468 (-2516 838);
PAINT GREEN (-2516 838);
DISPLAY INVISIBLE (-2516 838);
FORCEPROP 1 LAST LOCATION C6548
J 0
(-2150 825);
DISPLAY 1.021277 (-2150 825);
DISPLAY INVISIBLE (-2150 825);
FORCEADD Q_CAP_DIFFBUS..2
R 2
(-2400 800);
FORCEPROP 1 LAST LOCATION C6547
J 2
(-2125 800);
DISPLAY 0.723404 (-2125 800);
PAINT GREEN (-2125 800);
FORCEPROP 2 LAST $SEC 1
J 2
(-2225 875);
DISPLAY 0.680851 (-2225 875);
PAINT MONO (-2225 875);
DISPLAY INVISIBLE (-2225 875);
FORCEPROP 2 LAST CDS_SEC 1
J 2
(-2225 875);
DISPLAY 0.680851 (-2225 875);
DISPLAY INVISIBLE (-2225 875);
FORCEPROP 2 LASTPIN (-2325 800) $PN 1
J 0
(-2315 810);
DISPLAY 0.808511 (-2315 810);
FORCEPROP 2 LASTPIN (-2475 800) $PN 2
J 2
(-2485 810);
DISPLAY 0.808511 (-2485 810);
FORCEPROP 2 LAST VALUE DIFF BUS_0.22UF
J 2
(-2550 800);
DISPLAY 0.553191 (-2550 800);
FORCEPROP 1 LAST CDS_LMAN_SYM_OUTLINE -25,50,25,-50
J 2
(-2400 800);
DISPLAY 0.468085 (-2400 800);
PAINT GREEN (-2400 800);
DISPLAY INVISIBLE (-2400 800);
FORCEPROP 2 LAST CDS_LIB pure_quanta
J 2
(-2400 800);
DISPLAY INVISIBLE (-2400 800);
FORCEPROP 1 LAST PIN_NAMES_ROTATE TRUE
J 2
(-2400 800);
DISPLAY 0.489362 (-2400 800);
PAINT GREEN (-2400 800);
DISPLAY INVISIBLE (-2400 800);
FORCEPROP 2 LAST VOLTAGE 6.3V
J 2
(-2750 850);
DISPLAY 0.553191 (-2750 850);
DISPLAY INVISIBLE (-2750 850);
FORCEPROP 1 LAST MATERIAL X6S
J 2
(-2391 879);
DISPLAY 0.574468 (-2391 879);
PAINT GREEN (-2391 879);
DISPLAY INVISIBLE (-2391 879);
FORCEPROP 2 LAST PACK_TYPE C0201
J 2
(-2575 850);
DISPLAY 0.553191 (-2575 850);
DISPLAY INVISIBLE (-2575 850);
FORCEPROP 2 LAST TOLERANCE 20%
J 2
(-2475 850);
DISPLAY 0.553191 (-2475 850);
DISPLAY INVISIBLE (-2475 850);
FORCEPROP 1 LAST PATH I16
J 2
(-2400 800);
DISPLAY 0.723404 (-2400 800);
DISPLAY INVISIBLE (-2400 800);
FORCEPROP 1 LAST PART_NUMBER SP_CH4221MEE01
J 2
(-2516 888);
DISPLAY 0.574468 (-2516 888);
PAINT GREEN (-2516 888);
DISPLAY INVISIBLE (-2516 888);
FORCEPROP 1 LAST LOCATION C6547
J 0
(-2150 875);
DISPLAY 1.021277 (-2150 875);
DISPLAY INVISIBLE (-2150 875);
FORCEADD TAP..1
(-1650 750);
FORCEPROP 3 LASTPIN (-1700 750) SIG_NAME P5E_CPU0_P1_TX_BUF_C_DN<7>
J 0
(-1690 760);
DISPLAY 0.659574 (-1690 760);
PAINT MONO (-1690 760);
DISPLAY INVISIBLE (-1690 760);
FORCEPROP 1 LASTPIN (-1700 750) BN 7
J 0
(-1712 758);
DISPLAY 0.680851 (-1712 758);
PAINT GREEN (-1712 758);
FORCEPROP 2 LAST CDS_LIB standard
J 0
(-1650 750);
DISPLAY INVISIBLE (-1650 750);
FORCEPROP 1 LAST BODY_TYPE PLUMBING
J 0
(-1650 800);
DISPLAY 0.872340 (-1650 800);
PAINT GREEN (-1650 800);
DISPLAY INVISIBLE (-1650 800);
FORCEPROP 1 LAST HDL_TAP TRUE
J 0
(-1325 625);
DISPLAY 0.872340 (-1325 625);
DISPLAY INVISIBLE (-1325 625);
FORCEPROP 1 LAST PATH I17
J 0
(-1652 750);
DISPLAY 0.872340 (-1652 750);
PAINT GREEN (-1652 750);
DISPLAY INVISIBLE (-1652 750);
FORCEADD Q_CAP_DIFFBUS..2
R 2
(-2400 1000);
FORCEPROP 1 LAST LOCATION C6545
J 2
(-2125 1000);
DISPLAY 0.723404 (-2125 1000);
PAINT GREEN (-2125 1000);
FORCEPROP 2 LAST $SEC 1
J 2
(-2225 1075);
DISPLAY 0.680851 (-2225 1075);
PAINT MONO (-2225 1075);
DISPLAY INVISIBLE (-2225 1075);
FORCEPROP 2 LAST CDS_SEC 1
J 2
(-2225 1075);
DISPLAY 0.680851 (-2225 1075);
DISPLAY INVISIBLE (-2225 1075);
FORCEPROP 2 LASTPIN (-2325 1000) $PN 1
J 0
(-2315 1010);
DISPLAY 0.808511 (-2315 1010);
FORCEPROP 2 LASTPIN (-2475 1000) $PN 2
J 2
(-2485 1010);
DISPLAY 0.808511 (-2485 1010);
FORCEPROP 2 LAST VALUE DIFF BUS_0.22UF
J 2
(-2550 1000);
DISPLAY 0.553191 (-2550 1000);
FORCEPROP 2 LAST CDS_LIB pure_quanta
J 2
(-2400 1000);
DISPLAY INVISIBLE (-2400 1000);
FORCEPROP 1 LAST CDS_LMAN_SYM_OUTLINE -25,50,25,-50
J 2
(-2400 1000);
DISPLAY 0.468085 (-2400 1000);
PAINT GREEN (-2400 1000);
DISPLAY INVISIBLE (-2400 1000);
FORCEPROP 1 LAST PIN_NAMES_ROTATE TRUE
J 2
(-2400 1000);
DISPLAY 0.489362 (-2400 1000);
PAINT GREEN (-2400 1000);
DISPLAY INVISIBLE (-2400 1000);
FORCEPROP 2 LAST VOLTAGE 6.3V
J 2
(-2750 1050);
DISPLAY 0.553191 (-2750 1050);
DISPLAY INVISIBLE (-2750 1050);
FORCEPROP 1 LAST MATERIAL X6S
J 2
(-2391 1079);
DISPLAY 0.574468 (-2391 1079);
PAINT GREEN (-2391 1079);
DISPLAY INVISIBLE (-2391 1079);
FORCEPROP 2 LAST PACK_TYPE C0201
J 2
(-2575 1050);
DISPLAY 0.553191 (-2575 1050);
DISPLAY INVISIBLE (-2575 1050);
FORCEPROP 2 LAST TOLERANCE 20%
J 2
(-2475 1050);
DISPLAY 0.553191 (-2475 1050);
DISPLAY INVISIBLE (-2475 1050);
FORCEPROP 1 LAST PATH I18
J 2
(-2400 1000);
DISPLAY 0.723404 (-2400 1000);
DISPLAY INVISIBLE (-2400 1000);
FORCEPROP 1 LAST PART_NUMBER SP_CH4221MEE01
J 2
(-2516 1088);
DISPLAY 0.574468 (-2516 1088);
PAINT GREEN (-2516 1088);
DISPLAY INVISIBLE (-2516 1088);
FORCEPROP 1 LAST LOCATION C6545
J 0
(-2150 1075);
DISPLAY 1.021277 (-2150 1075);
DISPLAY INVISIBLE (-2150 1075);
FORCEADD Q_CAP_DIFFBUS..2
R 2
(-2400 950);
FORCEPROP 1 LAST LOCATION C6546
J 2
(-2125 950);
DISPLAY 0.723404 (-2125 950);
PAINT GREEN (-2125 950);
FORCEPROP 2 LAST $SEC 1
J 2
(-2225 1025);
DISPLAY 0.680851 (-2225 1025);
PAINT MONO (-2225 1025);
DISPLAY INVISIBLE (-2225 1025);
FORCEPROP 2 LAST CDS_SEC 1
J 2
(-2225 1025);
DISPLAY 0.680851 (-2225 1025);
DISPLAY INVISIBLE (-2225 1025);
FORCEPROP 2 LASTPIN (-2325 950) $PN 1
J 0
(-2315 960);
DISPLAY 0.808511 (-2315 960);
FORCEPROP 2 LASTPIN (-2475 950) $PN 2
J 2
(-2485 960);
DISPLAY 0.808511 (-2485 960);
FORCEPROP 2 LAST VALUE DIFF BUS_0.22UF
J 2
(-2550 950);
DISPLAY 0.553191 (-2550 950);
FORCEPROP 1 LAST CDS_LMAN_SYM_OUTLINE -25,50,25,-50
J 2
(-2400 950);
DISPLAY 0.468085 (-2400 950);
PAINT GREEN (-2400 950);
DISPLAY INVISIBLE (-2400 950);
FORCEPROP 2 LAST CDS_LIB pure_quanta
J 2
(-2400 950);
DISPLAY INVISIBLE (-2400 950);
FORCEPROP 1 LAST PIN_NAMES_ROTATE TRUE
J 2
(-2400 950);
DISPLAY 0.489362 (-2400 950);
PAINT GREEN (-2400 950);
DISPLAY INVISIBLE (-2400 950);
FORCEPROP 2 LAST VOLTAGE 6.3V
J 2
(-2750 1000);
DISPLAY 0.553191 (-2750 1000);
DISPLAY INVISIBLE (-2750 1000);
FORCEPROP 1 LAST MATERIAL X6S
J 2
(-2391 1029);
DISPLAY 0.574468 (-2391 1029);
PAINT GREEN (-2391 1029);
DISPLAY INVISIBLE (-2391 1029);
FORCEPROP 2 LAST PACK_TYPE C0201
J 2
(-2575 1000);
DISPLAY 0.553191 (-2575 1000);
DISPLAY INVISIBLE (-2575 1000);
FORCEPROP 2 LAST TOLERANCE 20%
J 2
(-2475 1000);
DISPLAY 0.553191 (-2475 1000);
DISPLAY INVISIBLE (-2475 1000);
FORCEPROP 1 LAST PATH I19
J 2
(-2400 950);
DISPLAY 0.723404 (-2400 950);
DISPLAY INVISIBLE (-2400 950);
FORCEPROP 1 LAST PART_NUMBER SP_CH4221MEE01
J 2
(-2516 1038);
DISPLAY 0.574468 (-2516 1038);
PAINT GREEN (-2516 1038);
DISPLAY INVISIBLE (-2516 1038);
FORCEPROP 1 LAST LOCATION C6546
J 0
(-2150 1025);
DISPLAY 1.021277 (-2150 1025);
DISPLAY INVISIBLE (-2150 1025);
FORCEADD OFFPAGE..1
(-4325 2225);
FORCEPROP 2 LAST $XR0 287 
J 0
(-4607 2225);
DISPLAY 0.638298 (-4607 2225);
PAINT MONO (-4607 2225);
FORCEPROP 2 LAST CDS_LIB standard
J 0
(-4325 2225);
DISPLAY INVISIBLE (-4325 2225);
FORCEPROP 1 LAST OFFPAGE TRUE
J 0
(-4000 2100);
DISPLAY 0.872340 (-4000 2100);
DISPLAY INVISIBLE (-4000 2100);
FORCEPROP 1 LAST COMMENT_BODY TRUE
J 0
(-4200 2125);
DISPLAY 0.872340 (-4200 2125);
PAINT GREEN (-4200 2125);
DISPLAY INVISIBLE (-4200 2125);
FORCEPROP 2 LAST PATH I2
J 0
(-4575 2275);
DISPLAY 0.680851 (-4575 2275);
DISPLAY INVISIBLE (-4575 2275);
FORCEADD Q_CAP_DIFFBUS..2
R 2
(-2400 1200);
FORCEPROP 1 LAST LOCATION C6543
J 2
(-2125 1200);
DISPLAY 0.723404 (-2125 1200);
PAINT GREEN (-2125 1200);
FORCEPROP 2 LAST $SEC 1
J 2
(-2225 1275);
DISPLAY 0.680851 (-2225 1275);
PAINT MONO (-2225 1275);
DISPLAY INVISIBLE (-2225 1275);
FORCEPROP 2 LAST CDS_SEC 1
J 2
(-2225 1275);
DISPLAY 0.680851 (-2225 1275);
DISPLAY INVISIBLE (-2225 1275);
FORCEPROP 2 LASTPIN (-2325 1200) $PN 1
J 0
(-2315 1210);
DISPLAY 0.808511 (-2315 1210);
FORCEPROP 2 LASTPIN (-2475 1200) $PN 2
J 2
(-2485 1210);
DISPLAY 0.808511 (-2485 1210);
FORCEPROP 2 LAST VALUE DIFF BUS_0.22UF
J 2
(-2550 1200);
DISPLAY 0.553191 (-2550 1200);
FORCEPROP 1 LAST CDS_LMAN_SYM_OUTLINE -25,50,25,-50
J 2
(-2400 1200);
DISPLAY 0.468085 (-2400 1200);
PAINT GREEN (-2400 1200);
DISPLAY INVISIBLE (-2400 1200);
FORCEPROP 2 LAST CDS_LIB pure_quanta
J 2
(-2400 1200);
DISPLAY INVISIBLE (-2400 1200);
FORCEPROP 1 LAST PIN_NAMES_ROTATE TRUE
J 2
(-2400 1200);
DISPLAY 0.489362 (-2400 1200);
PAINT GREEN (-2400 1200);
DISPLAY INVISIBLE (-2400 1200);
FORCEPROP 2 LAST VOLTAGE 6.3V
J 2
(-2750 1250);
DISPLAY 0.553191 (-2750 1250);
DISPLAY INVISIBLE (-2750 1250);
FORCEPROP 1 LAST MATERIAL X6S
J 2
(-2391 1279);
DISPLAY 0.574468 (-2391 1279);
PAINT GREEN (-2391 1279);
DISPLAY INVISIBLE (-2391 1279);
FORCEPROP 2 LAST PACK_TYPE C0201
J 2
(-2575 1250);
DISPLAY 0.553191 (-2575 1250);
DISPLAY INVISIBLE (-2575 1250);
FORCEPROP 2 LAST TOLERANCE 20%
J 2
(-2475 1250);
DISPLAY 0.553191 (-2475 1250);
DISPLAY INVISIBLE (-2475 1250);
FORCEPROP 1 LAST PATH I20
J 2
(-2400 1200);
DISPLAY 0.723404 (-2400 1200);
DISPLAY INVISIBLE (-2400 1200);
FORCEPROP 1 LAST PART_NUMBER SP_CH4221MEE01
J 2
(-2516 1288);
DISPLAY 0.574468 (-2516 1288);
PAINT GREEN (-2516 1288);
DISPLAY INVISIBLE (-2516 1288);
FORCEPROP 1 LAST LOCATION C6543
J 0
(-2150 1275);
DISPLAY 1.021277 (-2150 1275);
DISPLAY INVISIBLE (-2150 1275);
FORCEADD Q_CAP_DIFFBUS..2
R 2
(-2400 1150);
FORCEPROP 1 LAST LOCATION C6544
J 2
(-2125 1150);
DISPLAY 0.723404 (-2125 1150);
PAINT GREEN (-2125 1150);
FORCEPROP 2 LAST $SEC 1
J 2
(-2225 1225);
DISPLAY 0.680851 (-2225 1225);
PAINT MONO (-2225 1225);
DISPLAY INVISIBLE (-2225 1225);
FORCEPROP 2 LAST CDS_SEC 1
J 2
(-2225 1225);
DISPLAY 0.680851 (-2225 1225);
DISPLAY INVISIBLE (-2225 1225);
FORCEPROP 2 LASTPIN (-2325 1150) $PN 1
J 0
(-2315 1160);
DISPLAY 0.808511 (-2315 1160);
FORCEPROP 2 LASTPIN (-2475 1150) $PN 2
J 2
(-2485 1160);
DISPLAY 0.808511 (-2485 1160);
FORCEPROP 2 LAST VALUE DIFF BUS_0.22UF
J 2
(-2550 1150);
DISPLAY 0.553191 (-2550 1150);
FORCEPROP 1 LAST CDS_LMAN_SYM_OUTLINE -25,50,25,-50
J 2
(-2400 1150);
DISPLAY 0.468085 (-2400 1150);
PAINT GREEN (-2400 1150);
DISPLAY INVISIBLE (-2400 1150);
FORCEPROP 2 LAST CDS_LIB pure_quanta
J 2
(-2400 1150);
DISPLAY INVISIBLE (-2400 1150);
FORCEPROP 1 LAST PIN_NAMES_ROTATE TRUE
J 2
(-2400 1150);
DISPLAY 0.489362 (-2400 1150);
PAINT GREEN (-2400 1150);
DISPLAY INVISIBLE (-2400 1150);
FORCEPROP 2 LAST VOLTAGE 6.3V
J 2
(-2750 1200);
DISPLAY 0.553191 (-2750 1200);
DISPLAY INVISIBLE (-2750 1200);
FORCEPROP 1 LAST MATERIAL X6S
J 2
(-2391 1229);
DISPLAY 0.574468 (-2391 1229);
PAINT GREEN (-2391 1229);
DISPLAY INVISIBLE (-2391 1229);
FORCEPROP 2 LAST PACK_TYPE C0201
J 2
(-2575 1200);
DISPLAY 0.553191 (-2575 1200);
DISPLAY INVISIBLE (-2575 1200);
FORCEPROP 2 LAST TOLERANCE 20%
J 2
(-2475 1200);
DISPLAY 0.553191 (-2475 1200);
DISPLAY INVISIBLE (-2475 1200);
FORCEPROP 1 LAST PATH I21
J 2
(-2400 1150);
DISPLAY 0.723404 (-2400 1150);
DISPLAY INVISIBLE (-2400 1150);
FORCEPROP 1 LAST PART_NUMBER SP_CH4221MEE01
J 2
(-2516 1238);
DISPLAY 0.574468 (-2516 1238);
PAINT GREEN (-2516 1238);
DISPLAY INVISIBLE (-2516 1238);
FORCEPROP 1 LAST LOCATION C6544
J 0
(-2150 1225);
DISPLAY 1.021277 (-2150 1225);
DISPLAY INVISIBLE (-2150 1225);
FORCEADD Q_CAP_DIFFBUS..2
R 2
(-2400 1400);
FORCEPROP 1 LAST LOCATION C6541
J 2
(-2125 1400);
DISPLAY 0.723404 (-2125 1400);
PAINT GREEN (-2125 1400);
FORCEPROP 2 LAST $SEC 1
J 2
(-2225 1475);
DISPLAY 0.680851 (-2225 1475);
PAINT MONO (-2225 1475);
DISPLAY INVISIBLE (-2225 1475);
FORCEPROP 2 LAST CDS_SEC 1
J 2
(-2225 1475);
DISPLAY 0.680851 (-2225 1475);
DISPLAY INVISIBLE (-2225 1475);
FORCEPROP 2 LASTPIN (-2325 1400) $PN 1
J 0
(-2315 1410);
DISPLAY 0.808511 (-2315 1410);
FORCEPROP 2 LASTPIN (-2475 1400) $PN 2
J 2
(-2485 1410);
DISPLAY 0.808511 (-2485 1410);
FORCEPROP 2 LAST VALUE DIFF BUS_0.22UF
J 2
(-2550 1400);
DISPLAY 0.553191 (-2550 1400);
FORCEPROP 2 LAST CDS_LIB pure_quanta
J 2
(-2400 1400);
DISPLAY INVISIBLE (-2400 1400);
FORCEPROP 1 LAST CDS_LMAN_SYM_OUTLINE -25,50,25,-50
J 2
(-2400 1400);
DISPLAY 0.468085 (-2400 1400);
PAINT GREEN (-2400 1400);
DISPLAY INVISIBLE (-2400 1400);
FORCEPROP 1 LAST PIN_NAMES_ROTATE TRUE
J 2
(-2400 1400);
DISPLAY 0.489362 (-2400 1400);
PAINT GREEN (-2400 1400);
DISPLAY INVISIBLE (-2400 1400);
FORCEPROP 2 LAST VOLTAGE 6.3V
J 2
(-2750 1450);
DISPLAY 0.553191 (-2750 1450);
DISPLAY INVISIBLE (-2750 1450);
FORCEPROP 1 LAST MATERIAL X6S
J 2
(-2391 1479);
DISPLAY 0.574468 (-2391 1479);
PAINT GREEN (-2391 1479);
DISPLAY INVISIBLE (-2391 1479);
FORCEPROP 2 LAST PACK_TYPE C0201
J 2
(-2575 1450);
DISPLAY 0.553191 (-2575 1450);
DISPLAY INVISIBLE (-2575 1450);
FORCEPROP 2 LAST TOLERANCE 20%
J 2
(-2475 1450);
DISPLAY 0.553191 (-2475 1450);
DISPLAY INVISIBLE (-2475 1450);
FORCEPROP 1 LAST PATH I22
J 2
(-2400 1400);
DISPLAY 0.723404 (-2400 1400);
DISPLAY INVISIBLE (-2400 1400);
FORCEPROP 1 LAST PART_NUMBER SP_CH4221MEE01
J 2
(-2516 1488);
DISPLAY 0.574468 (-2516 1488);
PAINT GREEN (-2516 1488);
DISPLAY INVISIBLE (-2516 1488);
FORCEPROP 1 LAST LOCATION C6541
J 0
(-2150 1475);
DISPLAY 1.021277 (-2150 1475);
DISPLAY INVISIBLE (-2150 1475);
FORCEADD Q_CAP_DIFFBUS..2
R 2
(-2400 1350);
FORCEPROP 1 LAST LOCATION C6542
J 2
(-2125 1350);
DISPLAY 0.723404 (-2125 1350);
PAINT GREEN (-2125 1350);
FORCEPROP 2 LAST $SEC 1
J 2
(-2225 1425);
DISPLAY 0.680851 (-2225 1425);
PAINT MONO (-2225 1425);
DISPLAY INVISIBLE (-2225 1425);
FORCEPROP 2 LAST CDS_SEC 1
J 2
(-2225 1425);
DISPLAY 0.680851 (-2225 1425);
DISPLAY INVISIBLE (-2225 1425);
FORCEPROP 2 LASTPIN (-2325 1350) $PN 1
J 0
(-2315 1360);
DISPLAY 0.808511 (-2315 1360);
FORCEPROP 2 LASTPIN (-2475 1350) $PN 2
J 2
(-2485 1360);
DISPLAY 0.808511 (-2485 1360);
FORCEPROP 2 LAST VALUE DIFF BUS_0.22UF
J 2
(-2550 1350);
DISPLAY 0.553191 (-2550 1350);
FORCEPROP 2 LAST CDS_LIB pure_quanta
J 2
(-2400 1350);
DISPLAY INVISIBLE (-2400 1350);
FORCEPROP 1 LAST CDS_LMAN_SYM_OUTLINE -25,50,25,-50
J 2
(-2400 1350);
DISPLAY 0.468085 (-2400 1350);
PAINT GREEN (-2400 1350);
DISPLAY INVISIBLE (-2400 1350);
FORCEPROP 1 LAST PIN_NAMES_ROTATE TRUE
J 2
(-2400 1350);
DISPLAY 0.489362 (-2400 1350);
PAINT GREEN (-2400 1350);
DISPLAY INVISIBLE (-2400 1350);
FORCEPROP 2 LAST VOLTAGE 6.3V
J 2
(-2750 1400);
DISPLAY 0.553191 (-2750 1400);
DISPLAY INVISIBLE (-2750 1400);
FORCEPROP 1 LAST MATERIAL X6S
J 2
(-2391 1429);
DISPLAY 0.574468 (-2391 1429);
PAINT GREEN (-2391 1429);
DISPLAY INVISIBLE (-2391 1429);
FORCEPROP 2 LAST PACK_TYPE C0201
J 2
(-2575 1400);
DISPLAY 0.553191 (-2575 1400);
DISPLAY INVISIBLE (-2575 1400);
FORCEPROP 2 LAST TOLERANCE 20%
J 2
(-2475 1400);
DISPLAY 0.553191 (-2475 1400);
DISPLAY INVISIBLE (-2475 1400);
FORCEPROP 1 LAST PATH I23
J 2
(-2400 1350);
DISPLAY 0.723404 (-2400 1350);
DISPLAY INVISIBLE (-2400 1350);
FORCEPROP 1 LAST PART_NUMBER SP_CH4221MEE01
J 2
(-2516 1438);
DISPLAY 0.574468 (-2516 1438);
PAINT GREEN (-2516 1438);
DISPLAY INVISIBLE (-2516 1438);
FORCEPROP 1 LAST LOCATION C6542
J 0
(-2150 1425);
DISPLAY 1.021277 (-2150 1425);
DISPLAY INVISIBLE (-2150 1425);
FORCEADD Q_CAP_DIFFBUS..2
R 2
(-2400 1550);
FORCEPROP 1 LAST LOCATION C6540
J 2
(-2125 1550);
DISPLAY 0.723404 (-2125 1550);
PAINT GREEN (-2125 1550);
FORCEPROP 2 LAST $SEC 1
J 2
(-2225 1625);
DISPLAY 0.680851 (-2225 1625);
PAINT MONO (-2225 1625);
DISPLAY INVISIBLE (-2225 1625);
FORCEPROP 2 LAST CDS_SEC 1
J 2
(-2225 1625);
DISPLAY 0.680851 (-2225 1625);
DISPLAY INVISIBLE (-2225 1625);
FORCEPROP 2 LASTPIN (-2325 1550) $PN 1
J 0
(-2315 1560);
DISPLAY 0.808511 (-2315 1560);
FORCEPROP 2 LASTPIN (-2475 1550) $PN 2
J 2
(-2485 1560);
DISPLAY 0.808511 (-2485 1560);
FORCEPROP 2 LAST VALUE DIFF BUS_0.22UF
J 2
(-2550 1550);
DISPLAY 0.553191 (-2550 1550);
FORCEPROP 1 LAST CDS_LMAN_SYM_OUTLINE -25,50,25,-50
J 2
(-2400 1550);
DISPLAY 0.468085 (-2400 1550);
PAINT GREEN (-2400 1550);
DISPLAY INVISIBLE (-2400 1550);
FORCEPROP 2 LAST CDS_LIB pure_quanta
J 2
(-2400 1550);
DISPLAY INVISIBLE (-2400 1550);
FORCEPROP 1 LAST PIN_NAMES_ROTATE TRUE
J 2
(-2400 1550);
DISPLAY 0.489362 (-2400 1550);
PAINT GREEN (-2400 1550);
DISPLAY INVISIBLE (-2400 1550);
FORCEPROP 2 LAST VOLTAGE 6.3V
J 2
(-2750 1600);
DISPLAY 0.553191 (-2750 1600);
DISPLAY INVISIBLE (-2750 1600);
FORCEPROP 1 LAST MATERIAL X6S
J 2
(-2391 1629);
DISPLAY 0.574468 (-2391 1629);
PAINT GREEN (-2391 1629);
DISPLAY INVISIBLE (-2391 1629);
FORCEPROP 2 LAST PACK_TYPE C0201
J 2
(-2575 1600);
DISPLAY 0.553191 (-2575 1600);
DISPLAY INVISIBLE (-2575 1600);
FORCEPROP 2 LAST TOLERANCE 20%
J 2
(-2475 1600);
DISPLAY 0.553191 (-2475 1600);
DISPLAY INVISIBLE (-2475 1600);
FORCEPROP 1 LAST PATH I24
J 2
(-2400 1550);
DISPLAY 0.723404 (-2400 1550);
DISPLAY INVISIBLE (-2400 1550);
FORCEPROP 1 LAST PART_NUMBER SP_CH4221MEE01
J 2
(-2516 1638);
DISPLAY 0.574468 (-2516 1638);
PAINT GREEN (-2516 1638);
DISPLAY INVISIBLE (-2516 1638);
FORCEPROP 1 LAST LOCATION C6540
J 0
(-2150 1625);
DISPLAY 1.021277 (-2150 1625);
DISPLAY INVISIBLE (-2150 1625);
FORCEADD Q_CAP_DIFFBUS..2
R 2
(-2400 1600);
FORCEPROP 1 LAST LOCATION C6539
J 2
(-2125 1600);
DISPLAY 0.723404 (-2125 1600);
PAINT GREEN (-2125 1600);
FORCEPROP 2 LAST $SEC 1
J 2
(-2225 1675);
DISPLAY 0.680851 (-2225 1675);
PAINT MONO (-2225 1675);
DISPLAY INVISIBLE (-2225 1675);
FORCEPROP 2 LAST CDS_SEC 1
J 2
(-2225 1675);
DISPLAY 0.680851 (-2225 1675);
DISPLAY INVISIBLE (-2225 1675);
FORCEPROP 2 LASTPIN (-2325 1600) $PN 1
J 0
(-2315 1610);
DISPLAY 0.808511 (-2315 1610);
FORCEPROP 2 LASTPIN (-2475 1600) $PN 2
J 2
(-2485 1610);
DISPLAY 0.808511 (-2485 1610);
FORCEPROP 2 LAST VALUE DIFF BUS_0.22UF
J 2
(-2550 1600);
DISPLAY 0.553191 (-2550 1600);
FORCEPROP 1 LAST CDS_LMAN_SYM_OUTLINE -25,50,25,-50
J 2
(-2400 1600);
DISPLAY 0.468085 (-2400 1600);
PAINT GREEN (-2400 1600);
DISPLAY INVISIBLE (-2400 1600);
FORCEPROP 2 LAST CDS_LIB pure_quanta
J 2
(-2400 1600);
DISPLAY INVISIBLE (-2400 1600);
FORCEPROP 1 LAST PIN_NAMES_ROTATE TRUE
J 2
(-2400 1600);
DISPLAY 0.489362 (-2400 1600);
PAINT GREEN (-2400 1600);
DISPLAY INVISIBLE (-2400 1600);
FORCEPROP 2 LAST VOLTAGE 6.3V
J 2
(-2750 1650);
DISPLAY 0.553191 (-2750 1650);
DISPLAY INVISIBLE (-2750 1650);
FORCEPROP 1 LAST MATERIAL X6S
J 2
(-2391 1679);
DISPLAY 0.574468 (-2391 1679);
PAINT GREEN (-2391 1679);
DISPLAY INVISIBLE (-2391 1679);
FORCEPROP 2 LAST PACK_TYPE C0201
J 2
(-2575 1650);
DISPLAY 0.553191 (-2575 1650);
DISPLAY INVISIBLE (-2575 1650);
FORCEPROP 2 LAST TOLERANCE 20%
J 2
(-2475 1650);
DISPLAY 0.553191 (-2475 1650);
DISPLAY INVISIBLE (-2475 1650);
FORCEPROP 1 LAST PATH I25
J 2
(-2400 1600);
DISPLAY 0.723404 (-2400 1600);
DISPLAY INVISIBLE (-2400 1600);
FORCEPROP 1 LAST PART_NUMBER SP_CH4221MEE01
J 2
(-2516 1688);
DISPLAY 0.574468 (-2516 1688);
PAINT GREEN (-2516 1688);
DISPLAY INVISIBLE (-2516 1688);
FORCEPROP 1 LAST LOCATION C6539
J 0
(-2150 1675);
DISPLAY 1.021277 (-2150 1675);
DISPLAY INVISIBLE (-2150 1675);
FORCEADD Q_CAP_DIFFBUS..2
R 2
(-2400 1750);
FORCEPROP 1 LAST LOCATION C6538
J 2
(-2125 1750);
DISPLAY 0.723404 (-2125 1750);
PAINT GREEN (-2125 1750);
FORCEPROP 2 LAST $SEC 1
J 2
(-2225 1825);
DISPLAY 0.680851 (-2225 1825);
PAINT MONO (-2225 1825);
DISPLAY INVISIBLE (-2225 1825);
FORCEPROP 2 LAST CDS_SEC 1
J 2
(-2225 1825);
DISPLAY 0.680851 (-2225 1825);
DISPLAY INVISIBLE (-2225 1825);
FORCEPROP 2 LASTPIN (-2325 1750) $PN 1
J 0
(-2315 1760);
DISPLAY 0.808511 (-2315 1760);
FORCEPROP 2 LASTPIN (-2475 1750) $PN 2
J 2
(-2485 1760);
DISPLAY 0.808511 (-2485 1760);
FORCEPROP 2 LAST VALUE DIFF BUS_0.22UF
J 2
(-2550 1750);
DISPLAY 0.553191 (-2550 1750);
FORCEPROP 1 LAST CDS_LMAN_SYM_OUTLINE -25,50,25,-50
J 2
(-2400 1750);
DISPLAY 0.468085 (-2400 1750);
PAINT GREEN (-2400 1750);
DISPLAY INVISIBLE (-2400 1750);
FORCEPROP 2 LAST CDS_LIB pure_quanta
J 2
(-2400 1750);
DISPLAY INVISIBLE (-2400 1750);
FORCEPROP 1 LAST PIN_NAMES_ROTATE TRUE
J 2
(-2400 1750);
DISPLAY 0.489362 (-2400 1750);
PAINT GREEN (-2400 1750);
DISPLAY INVISIBLE (-2400 1750);
FORCEPROP 2 LAST VOLTAGE 6.3V
J 2
(-2750 1800);
DISPLAY 0.553191 (-2750 1800);
DISPLAY INVISIBLE (-2750 1800);
FORCEPROP 1 LAST MATERIAL X6S
J 2
(-2391 1829);
DISPLAY 0.574468 (-2391 1829);
PAINT GREEN (-2391 1829);
DISPLAY INVISIBLE (-2391 1829);
FORCEPROP 2 LAST PACK_TYPE C0201
J 2
(-2575 1800);
DISPLAY 0.553191 (-2575 1800);
DISPLAY INVISIBLE (-2575 1800);
FORCEPROP 2 LAST TOLERANCE 20%
J 2
(-2475 1800);
DISPLAY 0.553191 (-2475 1800);
DISPLAY INVISIBLE (-2475 1800);
FORCEPROP 1 LAST PATH I26
J 2
(-2400 1750);
DISPLAY 0.723404 (-2400 1750);
DISPLAY INVISIBLE (-2400 1750);
FORCEPROP 1 LAST PART_NUMBER SP_CH4221MEE01
J 2
(-2516 1838);
DISPLAY 0.574468 (-2516 1838);
PAINT GREEN (-2516 1838);
DISPLAY INVISIBLE (-2516 1838);
FORCEPROP 1 LAST LOCATION C6538
J 0
(-2150 1825);
DISPLAY 1.021277 (-2150 1825);
DISPLAY INVISIBLE (-2150 1825);
FORCEADD Q_CAP_DIFFBUS..2
R 2
(-2400 1800);
FORCEPROP 1 LAST LOCATION C6537
J 2
(-2125 1800);
DISPLAY 0.723404 (-2125 1800);
PAINT GREEN (-2125 1800);
FORCEPROP 2 LAST $SEC 1
J 2
(-2225 1875);
DISPLAY 0.680851 (-2225 1875);
PAINT MONO (-2225 1875);
DISPLAY INVISIBLE (-2225 1875);
FORCEPROP 2 LAST CDS_SEC 1
J 2
(-2225 1875);
DISPLAY 0.680851 (-2225 1875);
DISPLAY INVISIBLE (-2225 1875);
FORCEPROP 2 LASTPIN (-2325 1800) $PN 1
J 0
(-2315 1810);
DISPLAY 0.808511 (-2315 1810);
FORCEPROP 2 LASTPIN (-2475 1800) $PN 2
J 2
(-2485 1810);
DISPLAY 0.808511 (-2485 1810);
FORCEPROP 2 LAST VALUE DIFF BUS_0.22UF
J 2
(-2550 1800);
DISPLAY 0.553191 (-2550 1800);
FORCEPROP 1 LAST CDS_LMAN_SYM_OUTLINE -25,50,25,-50
J 2
(-2400 1800);
DISPLAY 0.468085 (-2400 1800);
PAINT GREEN (-2400 1800);
DISPLAY INVISIBLE (-2400 1800);
FORCEPROP 2 LAST CDS_LIB pure_quanta
J 2
(-2400 1800);
DISPLAY INVISIBLE (-2400 1800);
FORCEPROP 1 LAST PIN_NAMES_ROTATE TRUE
J 2
(-2400 1800);
DISPLAY 0.489362 (-2400 1800);
PAINT GREEN (-2400 1800);
DISPLAY INVISIBLE (-2400 1800);
FORCEPROP 2 LAST VOLTAGE 6.3V
J 2
(-2750 1850);
DISPLAY 0.553191 (-2750 1850);
DISPLAY INVISIBLE (-2750 1850);
FORCEPROP 1 LAST MATERIAL X6S
J 2
(-2391 1879);
DISPLAY 0.574468 (-2391 1879);
PAINT GREEN (-2391 1879);
DISPLAY INVISIBLE (-2391 1879);
FORCEPROP 2 LAST PACK_TYPE C0201
J 2
(-2575 1850);
DISPLAY 0.553191 (-2575 1850);
DISPLAY INVISIBLE (-2575 1850);
FORCEPROP 2 LAST TOLERANCE 20%
J 2
(-2475 1850);
DISPLAY 0.553191 (-2475 1850);
DISPLAY INVISIBLE (-2475 1850);
FORCEPROP 1 LAST PATH I27
J 2
(-2400 1800);
DISPLAY 0.723404 (-2400 1800);
DISPLAY INVISIBLE (-2400 1800);
FORCEPROP 1 LAST PART_NUMBER SP_CH4221MEE01
J 2
(-2516 1888);
DISPLAY 0.574468 (-2516 1888);
PAINT GREEN (-2516 1888);
DISPLAY INVISIBLE (-2516 1888);
FORCEPROP 1 LAST LOCATION C6537
J 0
(-2150 1875);
DISPLAY 1.021277 (-2150 1875);
DISPLAY INVISIBLE (-2150 1875);
FORCEADD TAP..1
(-1850 800);
FORCEPROP 3 LASTPIN (-1900 800) SIG_NAME P5E_CPU0_P1_TX_BUF_C_DP<7>
J 0
(-1890 810);
DISPLAY 0.659574 (-1890 810);
PAINT MONO (-1890 810);
DISPLAY INVISIBLE (-1890 810);
FORCEPROP 1 LASTPIN (-1900 800) BN 7
J 0
(-1912 808);
DISPLAY 0.680851 (-1912 808);
PAINT GREEN (-1912 808);
FORCEPROP 2 LAST CDS_LIB standard
J 0
(-1850 800);
DISPLAY INVISIBLE (-1850 800);
FORCEPROP 1 LAST BODY_TYPE PLUMBING
J 0
(-1850 850);
DISPLAY 0.872340 (-1850 850);
PAINT GREEN (-1850 850);
DISPLAY INVISIBLE (-1850 850);
FORCEPROP 1 LAST HDL_TAP TRUE
J 0
(-1525 675);
DISPLAY 0.872340 (-1525 675);
DISPLAY INVISIBLE (-1525 675);
FORCEPROP 1 LAST PATH I28
J 0
(-1852 800);
DISPLAY 0.872340 (-1852 800);
PAINT GREEN (-1852 800);
DISPLAY INVISIBLE (-1852 800);
FORCEADD TAP..1
(-1850 1200);
FORCEPROP 3 LASTPIN (-1900 1200) SIG_NAME P5E_CPU0_P1_TX_BUF_C_DP<5>
J 0
(-1890 1210);
DISPLAY 0.659574 (-1890 1210);
PAINT MONO (-1890 1210);
DISPLAY INVISIBLE (-1890 1210);
FORCEPROP 1 LASTPIN (-1900 1200) BN 5
J 0
(-1912 1208);
DISPLAY 0.680851 (-1912 1208);
PAINT GREEN (-1912 1208);
FORCEPROP 2 LAST CDS_LIB standard
J 0
(-1850 1200);
DISPLAY INVISIBLE (-1850 1200);
FORCEPROP 1 LAST BODY_TYPE PLUMBING
J 0
(-1850 1250);
DISPLAY 0.872340 (-1850 1250);
PAINT GREEN (-1850 1250);
DISPLAY INVISIBLE (-1850 1250);
FORCEPROP 1 LAST HDL_TAP TRUE
J 0
(-1525 1075);
DISPLAY 0.872340 (-1525 1075);
DISPLAY INVISIBLE (-1525 1075);
FORCEPROP 1 LAST PATH I29
J 0
(-1852 1200);
DISPLAY 0.872340 (-1852 1200);
PAINT GREEN (-1852 1200);
DISPLAY INVISIBLE (-1852 1200);
FORCEADD TAP..1
R 2
(-3375 750);
FORCEPROP 3 LASTPIN (-3325 750) SIG_NAME P5E_CPU0_P1_TX_BUF_DN<7>
J 0
(-3315 760);
DISPLAY 0.659574 (-3315 760);
PAINT MONO (-3315 760);
DISPLAY INVISIBLE (-3315 760);
FORCEPROP 1 LASTPIN (-3325 750) BN 7
J 2
(-3313 758);
DISPLAY 0.680851 (-3313 758);
PAINT GREEN (-3313 758);
FORCEPROP 2 LAST CDS_LIB standard
J 0
(-3375 750);
DISPLAY INVISIBLE (-3375 750);
FORCEPROP 1 LAST BODY_TYPE PLUMBING
J 2
(-3375 800);
DISPLAY 0.872340 (-3375 800);
PAINT GREEN (-3375 800);
DISPLAY INVISIBLE (-3375 800);
FORCEPROP 1 LAST HDL_TAP TRUE
J 2
(-3700 625);
DISPLAY 0.872340 (-3700 625);
DISPLAY INVISIBLE (-3700 625);
FORCEPROP 1 LAST PATH I3
J 2
(-3373 750);
DISPLAY 0.872340 (-3373 750);
PAINT GREEN (-3373 750);
DISPLAY INVISIBLE (-3373 750);
FORCEADD TAP..1
(-1850 1000);
FORCEPROP 3 LASTPIN (-1900 1000) SIG_NAME P5E_CPU0_P1_TX_BUF_C_DP<6>
J 0
(-1890 1010);
DISPLAY 0.659574 (-1890 1010);
PAINT MONO (-1890 1010);
DISPLAY INVISIBLE (-1890 1010);
FORCEPROP 1 LASTPIN (-1900 1000) BN 6
J 0
(-1912 1008);
DISPLAY 0.680851 (-1912 1008);
PAINT GREEN (-1912 1008);
FORCEPROP 2 LAST CDS_LIB standard
J 0
(-1850 1000);
DISPLAY INVISIBLE (-1850 1000);
FORCEPROP 1 LAST BODY_TYPE PLUMBING
J 0
(-1850 1050);
DISPLAY 0.872340 (-1850 1050);
PAINT GREEN (-1850 1050);
DISPLAY INVISIBLE (-1850 1050);
FORCEPROP 1 LAST HDL_TAP TRUE
J 0
(-1525 875);
DISPLAY 0.872340 (-1525 875);
DISPLAY INVISIBLE (-1525 875);
FORCEPROP 1 LAST PATH I30
J 0
(-1852 1000);
DISPLAY 0.872340 (-1852 1000);
PAINT GREEN (-1852 1000);
DISPLAY INVISIBLE (-1852 1000);
FORCEADD TAP..1
(-1650 950);
FORCEPROP 3 LASTPIN (-1700 950) SIG_NAME P5E_CPU0_P1_TX_BUF_C_DN<6>
J 0
(-1690 960);
DISPLAY 0.659574 (-1690 960);
PAINT MONO (-1690 960);
DISPLAY INVISIBLE (-1690 960);
FORCEPROP 1 LASTPIN (-1700 950) BN 6
J 0
(-1712 958);
DISPLAY 0.680851 (-1712 958);
PAINT GREEN (-1712 958);
FORCEPROP 2 LAST CDS_LIB standard
J 0
(-1650 950);
DISPLAY INVISIBLE (-1650 950);
FORCEPROP 1 LAST BODY_TYPE PLUMBING
J 0
(-1650 1000);
DISPLAY 0.872340 (-1650 1000);
PAINT GREEN (-1650 1000);
DISPLAY INVISIBLE (-1650 1000);
FORCEPROP 1 LAST HDL_TAP TRUE
J 0
(-1325 825);
DISPLAY 0.872340 (-1325 825);
DISPLAY INVISIBLE (-1325 825);
FORCEPROP 1 LAST PATH I31
J 0
(-1652 950);
DISPLAY 0.872340 (-1652 950);
PAINT GREEN (-1652 950);
DISPLAY INVISIBLE (-1652 950);
FORCEADD TAP..1
(-1650 1150);
FORCEPROP 3 LASTPIN (-1700 1150) SIG_NAME P5E_CPU0_P1_TX_BUF_C_DN<5>
J 0
(-1690 1160);
DISPLAY 0.659574 (-1690 1160);
PAINT MONO (-1690 1160);
DISPLAY INVISIBLE (-1690 1160);
FORCEPROP 1 LASTPIN (-1700 1150) BN 5
J 0
(-1712 1158);
DISPLAY 0.680851 (-1712 1158);
PAINT GREEN (-1712 1158);
FORCEPROP 2 LAST CDS_LIB standard
J 0
(-1650 1150);
DISPLAY INVISIBLE (-1650 1150);
FORCEPROP 1 LAST BODY_TYPE PLUMBING
J 0
(-1650 1200);
DISPLAY 0.872340 (-1650 1200);
PAINT GREEN (-1650 1200);
DISPLAY INVISIBLE (-1650 1200);
FORCEPROP 1 LAST HDL_TAP TRUE
J 0
(-1325 1025);
DISPLAY 0.872340 (-1325 1025);
DISPLAY INVISIBLE (-1325 1025);
FORCEPROP 1 LAST PATH I32
J 0
(-1652 1150);
DISPLAY 0.872340 (-1652 1150);
PAINT GREEN (-1652 1150);
DISPLAY INVISIBLE (-1652 1150);
FORCEADD TAP..1
(-1850 1600);
FORCEPROP 3 LASTPIN (-1900 1600) SIG_NAME P5E_CPU0_P1_TX_BUF_C_DP<3>
J 0
(-1890 1610);
DISPLAY 0.659574 (-1890 1610);
PAINT MONO (-1890 1610);
DISPLAY INVISIBLE (-1890 1610);
FORCEPROP 1 LASTPIN (-1900 1600) BN 3
J 0
(-1912 1608);
DISPLAY 0.680851 (-1912 1608);
PAINT GREEN (-1912 1608);
FORCEPROP 2 LAST CDS_LIB standard
J 0
(-1850 1600);
DISPLAY INVISIBLE (-1850 1600);
FORCEPROP 1 LAST BODY_TYPE PLUMBING
J 0
(-1850 1650);
DISPLAY 0.872340 (-1850 1650);
PAINT GREEN (-1850 1650);
DISPLAY INVISIBLE (-1850 1650);
FORCEPROP 1 LAST HDL_TAP TRUE
J 0
(-1525 1475);
DISPLAY 0.872340 (-1525 1475);
DISPLAY INVISIBLE (-1525 1475);
FORCEPROP 1 LAST PATH I33
J 0
(-1852 1600);
DISPLAY 0.872340 (-1852 1600);
PAINT GREEN (-1852 1600);
DISPLAY INVISIBLE (-1852 1600);
FORCEADD TAP..1
(-1850 1800);
FORCEPROP 3 LASTPIN (-1900 1800) SIG_NAME P5E_CPU0_P1_TX_BUF_C_DP<2>
J 0
(-1890 1810);
DISPLAY 0.659574 (-1890 1810);
PAINT MONO (-1890 1810);
DISPLAY INVISIBLE (-1890 1810);
FORCEPROP 1 LASTPIN (-1900 1800) BN 2
J 0
(-1912 1808);
DISPLAY 0.680851 (-1912 1808);
PAINT GREEN (-1912 1808);
FORCEPROP 2 LAST CDS_LIB standard
J 0
(-1850 1800);
DISPLAY INVISIBLE (-1850 1800);
FORCEPROP 1 LAST BODY_TYPE PLUMBING
J 0
(-1850 1850);
DISPLAY 0.872340 (-1850 1850);
PAINT GREEN (-1850 1850);
DISPLAY INVISIBLE (-1850 1850);
FORCEPROP 1 LAST HDL_TAP TRUE
J 0
(-1525 1675);
DISPLAY 0.872340 (-1525 1675);
DISPLAY INVISIBLE (-1525 1675);
FORCEPROP 1 LAST PATH I34
J 0
(-1852 1800);
DISPLAY 0.872340 (-1852 1800);
PAINT GREEN (-1852 1800);
DISPLAY INVISIBLE (-1852 1800);
FORCEADD TAP..1
(-1850 1400);
FORCEPROP 3 LASTPIN (-1900 1400) SIG_NAME P5E_CPU0_P1_TX_BUF_C_DP<4>
J 0
(-1890 1410);
DISPLAY 0.659574 (-1890 1410);
PAINT MONO (-1890 1410);
DISPLAY INVISIBLE (-1890 1410);
FORCEPROP 1 LASTPIN (-1900 1400) BN 4
J 0
(-1912 1408);
DISPLAY 0.680851 (-1912 1408);
PAINT GREEN (-1912 1408);
FORCEPROP 2 LAST CDS_LIB standard
J 0
(-1850 1400);
DISPLAY INVISIBLE (-1850 1400);
FORCEPROP 1 LAST BODY_TYPE PLUMBING
J 0
(-1850 1450);
DISPLAY 0.872340 (-1850 1450);
PAINT GREEN (-1850 1450);
DISPLAY INVISIBLE (-1850 1450);
FORCEPROP 1 LAST HDL_TAP TRUE
J 0
(-1525 1275);
DISPLAY 0.872340 (-1525 1275);
DISPLAY INVISIBLE (-1525 1275);
FORCEPROP 1 LAST PATH I35
J 0
(-1852 1400);
DISPLAY 0.872340 (-1852 1400);
PAINT GREEN (-1852 1400);
DISPLAY INVISIBLE (-1852 1400);
FORCEADD TAP..1
(-1650 1550);
FORCEPROP 3 LASTPIN (-1700 1550) SIG_NAME P5E_CPU0_P1_TX_BUF_C_DN<3>
J 0
(-1690 1560);
DISPLAY 0.659574 (-1690 1560);
PAINT MONO (-1690 1560);
DISPLAY INVISIBLE (-1690 1560);
FORCEPROP 1 LASTPIN (-1700 1550) BN 3
J 0
(-1712 1558);
DISPLAY 0.680851 (-1712 1558);
PAINT GREEN (-1712 1558);
FORCEPROP 2 LAST CDS_LIB standard
J 0
(-1650 1550);
DISPLAY INVISIBLE (-1650 1550);
FORCEPROP 1 LAST BODY_TYPE PLUMBING
J 0
(-1650 1600);
DISPLAY 0.872340 (-1650 1600);
PAINT GREEN (-1650 1600);
DISPLAY INVISIBLE (-1650 1600);
FORCEPROP 1 LAST HDL_TAP TRUE
J 0
(-1325 1425);
DISPLAY 0.872340 (-1325 1425);
DISPLAY INVISIBLE (-1325 1425);
FORCEPROP 1 LAST PATH I36
J 0
(-1652 1550);
DISPLAY 0.872340 (-1652 1550);
PAINT GREEN (-1652 1550);
DISPLAY INVISIBLE (-1652 1550);
FORCEADD TAP..1
(-1650 1350);
FORCEPROP 3 LASTPIN (-1700 1350) SIG_NAME P5E_CPU0_P1_TX_BUF_C_DN<4>
J 0
(-1690 1360);
DISPLAY 0.659574 (-1690 1360);
PAINT MONO (-1690 1360);
DISPLAY INVISIBLE (-1690 1360);
FORCEPROP 1 LASTPIN (-1700 1350) BN 4
J 0
(-1712 1358);
DISPLAY 0.680851 (-1712 1358);
PAINT GREEN (-1712 1358);
FORCEPROP 2 LAST CDS_LIB standard
J 0
(-1650 1350);
DISPLAY INVISIBLE (-1650 1350);
FORCEPROP 1 LAST BODY_TYPE PLUMBING
J 0
(-1650 1400);
DISPLAY 0.872340 (-1650 1400);
PAINT GREEN (-1650 1400);
DISPLAY INVISIBLE (-1650 1400);
FORCEPROP 1 LAST HDL_TAP TRUE
J 0
(-1325 1225);
DISPLAY 0.872340 (-1325 1225);
DISPLAY INVISIBLE (-1325 1225);
FORCEPROP 1 LAST PATH I37
J 0
(-1652 1350);
DISPLAY 0.872340 (-1652 1350);
PAINT GREEN (-1652 1350);
DISPLAY INVISIBLE (-1652 1350);
FORCEADD TAP..1
(-1650 1750);
FORCEPROP 3 LASTPIN (-1700 1750) SIG_NAME P5E_CPU0_P1_TX_BUF_C_DN<2>
J 0
(-1690 1760);
DISPLAY 0.659574 (-1690 1760);
PAINT MONO (-1690 1760);
DISPLAY INVISIBLE (-1690 1760);
FORCEPROP 1 LASTPIN (-1700 1750) BN 2
J 0
(-1712 1758);
DISPLAY 0.680851 (-1712 1758);
PAINT GREEN (-1712 1758);
FORCEPROP 2 LAST CDS_LIB standard
J 0
(-1650 1750);
DISPLAY INVISIBLE (-1650 1750);
FORCEPROP 1 LAST BODY_TYPE PLUMBING
J 0
(-1650 1800);
DISPLAY 0.872340 (-1650 1800);
PAINT GREEN (-1650 1800);
DISPLAY INVISIBLE (-1650 1800);
FORCEPROP 1 LAST HDL_TAP TRUE
J 0
(-1325 1625);
DISPLAY 0.872340 (-1325 1625);
DISPLAY INVISIBLE (-1325 1625);
FORCEPROP 1 LAST PATH I38
J 0
(-1652 1750);
DISPLAY 0.872340 (-1652 1750);
PAINT GREEN (-1652 1750);
DISPLAY INVISIBLE (-1652 1750);
FORCEADD TAP..1
R 2
(-3375 1950);
FORCEPROP 3 LASTPIN (-3325 1950) SIG_NAME P5E_CPU0_P1_TX_BUF_DN<1>
J 0
(-3315 1960);
DISPLAY 0.659574 (-3315 1960);
PAINT MONO (-3315 1960);
DISPLAY INVISIBLE (-3315 1960);
FORCEPROP 1 LASTPIN (-3325 1950) BN 1
J 2
(-3313 1958);
DISPLAY 0.680851 (-3313 1958);
PAINT GREEN (-3313 1958);
FORCEPROP 2 LAST CDS_LIB standard
J 0
(-3375 1950);
DISPLAY INVISIBLE (-3375 1950);
FORCEPROP 1 LAST BODY_TYPE PLUMBING
J 2
(-3375 2000);
DISPLAY 0.872340 (-3375 2000);
PAINT GREEN (-3375 2000);
DISPLAY INVISIBLE (-3375 2000);
FORCEPROP 1 LAST HDL_TAP TRUE
J 2
(-3700 1825);
DISPLAY 0.872340 (-3700 1825);
DISPLAY INVISIBLE (-3700 1825);
FORCEPROP 1 LAST PATH I39
J 2
(-3373 1950);
DISPLAY 0.872340 (-3373 1950);
PAINT GREEN (-3373 1950);
DISPLAY INVISIBLE (-3373 1950);
FORCEADD TAP..1
R 2
(-3375 950);
FORCEPROP 3 LASTPIN (-3325 950) SIG_NAME P5E_CPU0_P1_TX_BUF_DN<6>
J 0
(-3315 960);
DISPLAY 0.659574 (-3315 960);
PAINT MONO (-3315 960);
DISPLAY INVISIBLE (-3315 960);
FORCEPROP 1 LASTPIN (-3325 950) BN 6
J 2
(-3313 958);
DISPLAY 0.680851 (-3313 958);
PAINT GREEN (-3313 958);
FORCEPROP 2 LAST CDS_LIB standard
J 0
(-3375 950);
DISPLAY INVISIBLE (-3375 950);
FORCEPROP 1 LAST BODY_TYPE PLUMBING
J 2
(-3375 1000);
DISPLAY 0.872340 (-3375 1000);
PAINT GREEN (-3375 1000);
DISPLAY INVISIBLE (-3375 1000);
FORCEPROP 1 LAST HDL_TAP TRUE
J 2
(-3700 825);
DISPLAY 0.872340 (-3700 825);
DISPLAY INVISIBLE (-3700 825);
FORCEPROP 1 LAST PATH I4
J 2
(-3373 950);
DISPLAY 0.872340 (-3373 950);
PAINT GREEN (-3373 950);
DISPLAY INVISIBLE (-3373 950);
FORCEADD TAP..1
R 2
(-3375 2150);
FORCEPROP 3 LASTPIN (-3325 2150) SIG_NAME P5E_CPU0_P1_TX_BUF_DN<0>
J 0
(-3315 2160);
DISPLAY 0.659574 (-3315 2160);
PAINT MONO (-3315 2160);
DISPLAY INVISIBLE (-3315 2160);
FORCEPROP 1 LASTPIN (-3325 2150) BN 0
J 2
(-3313 2158);
DISPLAY 0.680851 (-3313 2158);
PAINT GREEN (-3313 2158);
FORCEPROP 2 LAST CDS_LIB standard
J 0
(-3375 2150);
DISPLAY INVISIBLE (-3375 2150);
FORCEPROP 1 LAST BODY_TYPE PLUMBING
J 2
(-3375 2200);
DISPLAY 0.872340 (-3375 2200);
PAINT GREEN (-3375 2200);
DISPLAY INVISIBLE (-3375 2200);
FORCEPROP 1 LAST HDL_TAP TRUE
J 2
(-3700 2025);
DISPLAY 0.872340 (-3700 2025);
DISPLAY INVISIBLE (-3700 2025);
FORCEPROP 1 LAST PATH I40
J 2
(-3373 2150);
DISPLAY 0.872340 (-3373 2150);
PAINT GREEN (-3373 2150);
DISPLAY INVISIBLE (-3373 2150);
FORCEADD TAP..1
R 2
(-3125 2000);
FORCEPROP 3 LASTPIN (-3075 2000) SIG_NAME P5E_CPU0_P1_TX_BUF_DP<1>
J 0
(-3065 2010);
DISPLAY 0.659574 (-3065 2010);
PAINT MONO (-3065 2010);
DISPLAY INVISIBLE (-3065 2010);
FORCEPROP 1 LASTPIN (-3075 2000) BN 1
J 2
(-3063 2008);
DISPLAY 0.680851 (-3063 2008);
PAINT GREEN (-3063 2008);
FORCEPROP 2 LAST CDS_LIB standard
J 0
(-3125 2000);
DISPLAY INVISIBLE (-3125 2000);
FORCEPROP 1 LAST BODY_TYPE PLUMBING
J 2
(-3125 2050);
DISPLAY 0.872340 (-3125 2050);
PAINT GREEN (-3125 2050);
DISPLAY INVISIBLE (-3125 2050);
FORCEPROP 1 LAST HDL_TAP TRUE
J 2
(-3450 1875);
DISPLAY 0.872340 (-3450 1875);
DISPLAY INVISIBLE (-3450 1875);
FORCEPROP 1 LAST PATH I41
J 2
(-3123 2000);
DISPLAY 0.872340 (-3123 2000);
PAINT GREEN (-3123 2000);
DISPLAY INVISIBLE (-3123 2000);
FORCEADD TAP..1
R 2
(-3125 2200);
FORCEPROP 3 LASTPIN (-3075 2200) SIG_NAME P5E_CPU0_P1_TX_BUF_DP<0>
J 0
(-3065 2210);
DISPLAY 0.659574 (-3065 2210);
PAINT MONO (-3065 2210);
DISPLAY INVISIBLE (-3065 2210);
FORCEPROP 1 LASTPIN (-3075 2200) BN 0
J 2
(-3063 2208);
DISPLAY 0.680851 (-3063 2208);
PAINT GREEN (-3063 2208);
FORCEPROP 2 LAST CDS_LIB standard
J 0
(-3125 2200);
DISPLAY INVISIBLE (-3125 2200);
FORCEPROP 1 LAST BODY_TYPE PLUMBING
J 2
(-3125 2250);
DISPLAY 0.872340 (-3125 2250);
PAINT GREEN (-3125 2250);
DISPLAY INVISIBLE (-3125 2250);
FORCEPROP 1 LAST HDL_TAP TRUE
J 2
(-3450 2075);
DISPLAY 0.872340 (-3450 2075);
DISPLAY INVISIBLE (-3450 2075);
FORCEPROP 1 LAST PATH I42
J 2
(-3123 2200);
DISPLAY 0.872340 (-3123 2200);
PAINT GREEN (-3123 2200);
DISPLAY INVISIBLE (-3123 2200);
FORCEADD PT5161LRS..10
(-7775 4575);
FORCEPROP 1 LAST LOCATION U6011
J 0
(-8125 6200);
DISPLAY 0.723404 (-8125 6200);
PAINT GREEN (-8125 6200);
FORCEPROP 0 LAST $SEC 10
J 0
(-8125 6350);
DISPLAY 0.680851 (-8125 6350);
PAINT MONO (-8125 6350);
DISPLAY INVISIBLE (-8125 6350);
FORCEPROP 0 LAST CDS_SEC 10
J 0
(-8125 6350);
DISPLAY 0.680851 (-8125 6350);
DISPLAY INVISIBLE (-8125 6350);
FORCEPROP 0 LASTPIN (-7325 5725) $PN P10
J 0
(-7315 5735);
DISPLAY 0.680851 (-7315 5735);
PAINT MONO (-7315 5735);
FORCEPROP 0 LASTPIN (-7325 5375) $PN AA10
J 0
(-7315 5385);
DISPLAY 0.680851 (-7315 5385);
PAINT MONO (-7315 5385);
FORCEPROP 0 LASTPIN (-7325 5025) $PN AH10
J 0
(-7315 5035);
DISPLAY 0.680851 (-7315 5035);
PAINT MONO (-7315 5035);
FORCEPROP 0 LASTPIN (-7325 4675) $PN AR10
J 0
(-7315 4685);
DISPLAY 0.680851 (-7315 4685);
PAINT MONO (-7315 4685);
FORCEPROP 0 LASTPIN (-7325 4325) $PN BB10
J 0
(-7315 4335);
DISPLAY 0.680851 (-7315 4335);
PAINT MONO (-7315 4335);
FORCEPROP 0 LASTPIN (-7325 3975) $PN BJ10
J 0
(-7315 3985);
DISPLAY 0.680851 (-7315 3985);
PAINT MONO (-7315 3985);
FORCEPROP 0 LASTPIN (-7325 3625) $PN BT10
J 0
(-7315 3635);
DISPLAY 0.680851 (-7315 3635);
PAINT MONO (-7315 3635);
FORCEPROP 0 LASTPIN (-7325 3275) $PN CC10
J 0
(-7315 3285);
DISPLAY 0.680851 (-7315 3285);
PAINT MONO (-7315 3285);
FORCEPROP 0 LASTPIN (-7325 5825) $PN M7
J 0
(-7315 5835);
DISPLAY 0.680851 (-7315 5835);
PAINT MONO (-7315 5835);
FORCEPROP 0 LASTPIN (-7325 5475) $PN W7
J 0
(-7315 5485);
DISPLAY 0.680851 (-7315 5485);
PAINT MONO (-7315 5485);
FORCEPROP 0 LASTPIN (-7325 5125) $PN AF7
J 0
(-7315 5135);
DISPLAY 0.680851 (-7315 5135);
PAINT MONO (-7315 5135);
FORCEPROP 0 LASTPIN (-7325 4775) $PN AN7
J 0
(-7315 4785);
DISPLAY 0.680851 (-7315 4785);
PAINT MONO (-7315 4785);
FORCEPROP 0 LASTPIN (-7325 4425) $PN AY7
J 0
(-7315 4435);
DISPLAY 0.680851 (-7315 4435);
PAINT MONO (-7315 4435);
FORCEPROP 0 LASTPIN (-7325 4075) $PN BG7
J 0
(-7315 4085);
DISPLAY 0.680851 (-7315 4085);
PAINT MONO (-7315 4085);
FORCEPROP 0 LASTPIN (-7325 3725) $PN BP7
J 0
(-7315 3735);
DISPLAY 0.680851 (-7315 3735);
PAINT MONO (-7315 3735);
FORCEPROP 0 LASTPIN (-7325 3375) $PN CA7
J 0
(-7315 3385);
DISPLAY 0.680851 (-7315 3385);
PAINT MONO (-7315 3385);
FORCEPROP 1 LAST MATERIAL IC
J 0
(-8125 6050);
DISPLAY 0.723404 (-8125 6050);
PAINT GREEN (-8125 6050);
FORCEPROP 2 LAST PART_TYPE SMLF
J 0
(-8125 6300);
DISPLAY 0.680851 (-8125 6300);
FORCEPROP 2 LAST VALUE PT5161LRS
J 0
(-8125 6250);
DISPLAY 0.680851 (-8125 6250);
FORCEPROP 1 LAST NEEDS_NO_SIZE TRUE
J 0
(-7775 4575);
DISPLAY 0.723404 (-7775 4575);
PAINT GREEN (-7775 4575);
DISPLAY INVISIBLE (-7775 4575);
FORCEPROP 1 LAST CDS_LMAN_SYM_OUTLINE -350,1450,300,-1400
J 0
(-7775 4575);
DISPLAY 0.468085 (-7775 4575);
PAINT GREEN (-7775 4575);
DISPLAY INVISIBLE (-7775 4575);
FORCEPROP 2 LAST CDS_LIB pure_quanta
J 0
(-7775 4575);
DISPLAY INVISIBLE (-7775 4575);
FORCEPROP 1 LAST PATH I43
J 0
(-7775 4575);
DISPLAY 0.723404 (-7775 4575);
PAINT GREEN (-7775 4575);
DISPLAY INVISIBLE (-7775 4575);
FORCEPROP 1 LAST PART_NUMBER AJ051610U03
J 0
(-8125 6125);
DISPLAY 0.723404 (-8125 6125);
PAINT GREEN (-8125 6125);
DISPLAY INVISIBLE (-8125 6125);
FORCEADD Q_CAP_DIFFBUS..2
R 2
(-2400 1950);
FORCEPROP 1 LAST LOCATION C6536
J 2
(-2100 1950);
DISPLAY 0.723404 (-2100 1950);
PAINT GREEN (-2100 1950);
FORCEPROP 2 LAST $SEC 1
J 2
(-2225 2025);
DISPLAY 0.680851 (-2225 2025);
PAINT MONO (-2225 2025);
DISPLAY INVISIBLE (-2225 2025);
FORCEPROP 2 LAST CDS_SEC 1
J 2
(-2225 2025);
DISPLAY 0.680851 (-2225 2025);
DISPLAY INVISIBLE (-2225 2025);
FORCEPROP 2 LASTPIN (-2325 1950) $PN 1
J 0
(-2315 1960);
DISPLAY 0.808511 (-2315 1960);
FORCEPROP 2 LASTPIN (-2475 1950) $PN 2
J 2
(-2485 1960);
DISPLAY 0.808511 (-2485 1960);
FORCEPROP 2 LAST VALUE DIFF BUS_0.22UF
J 2
(-2550 1950);
DISPLAY 0.553191 (-2550 1950);
FORCEPROP 1 LAST CDS_LMAN_SYM_OUTLINE -25,50,25,-50
J 2
(-2400 1950);
DISPLAY 0.468085 (-2400 1950);
PAINT GREEN (-2400 1950);
DISPLAY INVISIBLE (-2400 1950);
FORCEPROP 2 LAST CDS_LIB pure_quanta
J 2
(-2400 1950);
DISPLAY INVISIBLE (-2400 1950);
FORCEPROP 1 LAST PIN_NAMES_ROTATE TRUE
J 2
(-2400 1950);
DISPLAY 0.489362 (-2400 1950);
PAINT GREEN (-2400 1950);
DISPLAY INVISIBLE (-2400 1950);
FORCEPROP 2 LAST VOLTAGE 6.3V
J 2
(-2750 2000);
DISPLAY 0.553191 (-2750 2000);
DISPLAY INVISIBLE (-2750 2000);
FORCEPROP 1 LAST MATERIAL X6S
J 2
(-2391 2029);
DISPLAY 0.574468 (-2391 2029);
PAINT GREEN (-2391 2029);
DISPLAY INVISIBLE (-2391 2029);
FORCEPROP 2 LAST PACK_TYPE C0201
J 2
(-2575 2000);
DISPLAY 0.553191 (-2575 2000);
DISPLAY INVISIBLE (-2575 2000);
FORCEPROP 2 LAST TOLERANCE 20%
J 2
(-2475 2000);
DISPLAY 0.553191 (-2475 2000);
DISPLAY INVISIBLE (-2475 2000);
FORCEPROP 1 LAST PATH I44
J 2
(-2400 1950);
DISPLAY 0.723404 (-2400 1950);
DISPLAY INVISIBLE (-2400 1950);
FORCEPROP 1 LAST PART_NUMBER SP_CH4221MEE01
J 2
(-2516 2038);
DISPLAY 0.574468 (-2516 2038);
PAINT GREEN (-2516 2038);
DISPLAY INVISIBLE (-2516 2038);
FORCEPROP 1 LAST LOCATION C6536
J 0
(-2150 2025);
DISPLAY 1.021277 (-2150 2025);
DISPLAY INVISIBLE (-2150 2025);
FORCEADD Q_CAP_DIFFBUS..2
R 2
(-2400 2000);
FORCEPROP 1 LAST LOCATION C6535
J 2
(-2100 2000);
DISPLAY 0.723404 (-2100 2000);
PAINT GREEN (-2100 2000);
FORCEPROP 2 LAST $SEC 1
J 2
(-2225 2075);
DISPLAY 0.680851 (-2225 2075);
PAINT MONO (-2225 2075);
DISPLAY INVISIBLE (-2225 2075);
FORCEPROP 2 LAST CDS_SEC 1
J 2
(-2225 2075);
DISPLAY 0.680851 (-2225 2075);
DISPLAY INVISIBLE (-2225 2075);
FORCEPROP 2 LASTPIN (-2325 2000) $PN 1
J 0
(-2315 2010);
DISPLAY 0.808511 (-2315 2010);
FORCEPROP 2 LASTPIN (-2475 2000) $PN 2
J 2
(-2485 2010);
DISPLAY 0.808511 (-2485 2010);
FORCEPROP 2 LAST VALUE DIFF BUS_0.22UF
J 2
(-2550 2000);
DISPLAY 0.553191 (-2550 2000);
FORCEPROP 1 LAST CDS_LMAN_SYM_OUTLINE -25,50,25,-50
J 2
(-2400 2000);
DISPLAY 0.468085 (-2400 2000);
PAINT GREEN (-2400 2000);
DISPLAY INVISIBLE (-2400 2000);
FORCEPROP 2 LAST CDS_LIB pure_quanta
J 2
(-2400 2000);
DISPLAY INVISIBLE (-2400 2000);
FORCEPROP 1 LAST PIN_NAMES_ROTATE TRUE
J 2
(-2400 2000);
DISPLAY 0.489362 (-2400 2000);
PAINT GREEN (-2400 2000);
DISPLAY INVISIBLE (-2400 2000);
FORCEPROP 2 LAST VOLTAGE 6.3V
J 2
(-2750 2050);
DISPLAY 0.553191 (-2750 2050);
DISPLAY INVISIBLE (-2750 2050);
FORCEPROP 1 LAST MATERIAL X6S
J 2
(-2391 2079);
DISPLAY 0.574468 (-2391 2079);
PAINT GREEN (-2391 2079);
DISPLAY INVISIBLE (-2391 2079);
FORCEPROP 2 LAST PACK_TYPE C0201
J 2
(-2575 2050);
DISPLAY 0.553191 (-2575 2050);
DISPLAY INVISIBLE (-2575 2050);
FORCEPROP 2 LAST TOLERANCE 20%
J 2
(-2475 2050);
DISPLAY 0.553191 (-2475 2050);
DISPLAY INVISIBLE (-2475 2050);
FORCEPROP 1 LAST PATH I45
J 2
(-2400 2000);
DISPLAY 0.723404 (-2400 2000);
DISPLAY INVISIBLE (-2400 2000);
FORCEPROP 1 LAST PART_NUMBER SP_CH4221MEE01
J 2
(-2516 2088);
DISPLAY 0.574468 (-2516 2088);
PAINT GREEN (-2516 2088);
DISPLAY INVISIBLE (-2516 2088);
FORCEPROP 1 LAST LOCATION C6535
J 0
(-2150 2075);
DISPLAY 1.021277 (-2150 2075);
DISPLAY INVISIBLE (-2150 2075);
FORCEADD Q_CAP_DIFFBUS..2
R 2
(-2400 2200);
FORCEPROP 1 LAST LOCATION C6533
J 2
(-2100 2200);
DISPLAY 0.723404 (-2100 2200);
PAINT GREEN (-2100 2200);
FORCEPROP 2 LAST $SEC 1
J 2
(-2225 2275);
DISPLAY 0.680851 (-2225 2275);
PAINT MONO (-2225 2275);
DISPLAY INVISIBLE (-2225 2275);
FORCEPROP 2 LAST CDS_SEC 1
J 2
(-2225 2275);
DISPLAY 0.680851 (-2225 2275);
DISPLAY INVISIBLE (-2225 2275);
FORCEPROP 2 LASTPIN (-2325 2200) $PN 1
J 0
(-2315 2210);
DISPLAY 0.808511 (-2315 2210);
FORCEPROP 2 LASTPIN (-2475 2200) $PN 2
J 2
(-2485 2210);
DISPLAY 0.808511 (-2485 2210);
FORCEPROP 2 LAST VALUE DIFF BUS_0.22UF
J 2
(-2550 2200);
DISPLAY 0.553191 (-2550 2200);
FORCEPROP 2 LAST PACK_TYPE C0201
J 2
(-2450 2350);
DISPLAY 0.553191 (-2450 2350);
PAINT GREEN (-2450 2350);
FORCEPROP 1 LAST MATERIAL X6S
J 2
(-2491 2404);
DISPLAY 0.574468 (-2491 2404);
PAINT GREEN (-2491 2404);
FORCEPROP 2 LAST VOLTAGE 6.3V
J 2
(-2225 2350);
DISPLAY 0.553191 (-2225 2350);
PAINT GREEN (-2225 2350);
FORCEPROP 2 LAST TOLERANCE 20%
J 2
(-2350 2350);
DISPLAY 0.553191 (-2350 2350);
PAINT GREEN (-2350 2350);
FORCEPROP 2 LAST CDS_LIB pure_quanta
J 2
(-2400 2200);
DISPLAY INVISIBLE (-2400 2200);
FORCEPROP 1 LAST CDS_LMAN_SYM_OUTLINE -25,50,25,-50
J 2
(-2400 2200);
DISPLAY 0.468085 (-2400 2200);
PAINT GREEN (-2400 2200);
DISPLAY INVISIBLE (-2400 2200);
FORCEPROP 1 LAST PIN_NAMES_ROTATE TRUE
J 2
(-2400 2200);
DISPLAY 0.489362 (-2400 2200);
PAINT GREEN (-2400 2200);
DISPLAY INVISIBLE (-2400 2200);
FORCEPROP 1 LAST PATH I46
J 2
(-2400 2200);
DISPLAY 0.723404 (-2400 2200);
DISPLAY INVISIBLE (-2400 2200);
FORCEPROP 1 LAST PART_NUMBER SP_CH4221MEE01
J 2
(-2216 2288);
DISPLAY 0.574468 (-2216 2288);
PAINT GREEN (-2216 2288);
DISPLAY INVISIBLE (-2216 2288);
FORCEPROP 1 LAST LOCATION C6533
J 0
(-2150 2275);
DISPLAY 1.021277 (-2150 2275);
DISPLAY INVISIBLE (-2150 2275);
FORCEADD Q_CAP_DIFFBUS..2
R 2
(-2400 2150);
FORCEPROP 1 LAST LOCATION C6534
J 2
(-2100 2150);
DISPLAY 0.723404 (-2100 2150);
PAINT GREEN (-2100 2150);
FORCEPROP 2 LAST $SEC 1
J 2
(-2225 2225);
DISPLAY 0.680851 (-2225 2225);
PAINT MONO (-2225 2225);
DISPLAY INVISIBLE (-2225 2225);
FORCEPROP 2 LAST CDS_SEC 1
J 2
(-2225 2225);
DISPLAY 0.680851 (-2225 2225);
DISPLAY INVISIBLE (-2225 2225);
FORCEPROP 2 LASTPIN (-2325 2150) $PN 1
J 0
(-2315 2160);
DISPLAY 0.808511 (-2315 2160);
FORCEPROP 2 LASTPIN (-2475 2150) $PN 2
J 2
(-2485 2160);
DISPLAY 0.808511 (-2485 2160);
FORCEPROP 2 LAST VALUE DIFF BUS_0.22UF
J 2
(-2550 2150);
DISPLAY 0.553191 (-2550 2150);
FORCEPROP 1 LAST CDS_LMAN_SYM_OUTLINE -25,50,25,-50
J 2
(-2400 2150);
DISPLAY 0.468085 (-2400 2150);
PAINT GREEN (-2400 2150);
DISPLAY INVISIBLE (-2400 2150);
FORCEPROP 2 LAST CDS_LIB pure_quanta
J 2
(-2400 2150);
DISPLAY INVISIBLE (-2400 2150);
FORCEPROP 1 LAST PIN_NAMES_ROTATE TRUE
J 2
(-2400 2150);
DISPLAY 0.489362 (-2400 2150);
PAINT GREEN (-2400 2150);
DISPLAY INVISIBLE (-2400 2150);
FORCEPROP 2 LAST VOLTAGE 6.3V
J 2
(-2750 2200);
DISPLAY 0.553191 (-2750 2200);
DISPLAY INVISIBLE (-2750 2200);
FORCEPROP 1 LAST MATERIAL X6S
J 2
(-2391 2229);
DISPLAY 0.574468 (-2391 2229);
PAINT GREEN (-2391 2229);
DISPLAY INVISIBLE (-2391 2229);
FORCEPROP 2 LAST PACK_TYPE C0201
J 2
(-2575 2200);
DISPLAY 0.553191 (-2575 2200);
DISPLAY INVISIBLE (-2575 2200);
FORCEPROP 2 LAST TOLERANCE 20%
J 2
(-2475 2200);
DISPLAY 0.553191 (-2475 2200);
DISPLAY INVISIBLE (-2475 2200);
FORCEPROP 1 LAST PATH I47
J 2
(-2400 2150);
DISPLAY 0.723404 (-2400 2150);
DISPLAY INVISIBLE (-2400 2150);
FORCEPROP 1 LAST PART_NUMBER SP_CH4221MEE01
J 2
(-2516 2238);
DISPLAY 0.574468 (-2516 2238);
PAINT GREEN (-2516 2238);
DISPLAY INVISIBLE (-2516 2238);
FORCEPROP 1 LAST LOCATION C6534
J 0
(-2150 2225);
DISPLAY 1.021277 (-2150 2225);
DISPLAY INVISIBLE (-2150 2225);
FORCEADD TAP..1
(-1850 2000);
FORCEPROP 3 LASTPIN (-1900 2000) SIG_NAME P5E_CPU0_P1_TX_BUF_C_DP<1>
J 0
(-1890 2010);
DISPLAY 0.659574 (-1890 2010);
PAINT MONO (-1890 2010);
DISPLAY INVISIBLE (-1890 2010);
FORCEPROP 1 LASTPIN (-1900 2000) BN 1
J 0
(-1912 2008);
DISPLAY 0.680851 (-1912 2008);
PAINT GREEN (-1912 2008);
FORCEPROP 2 LAST CDS_LIB standard
J 0
(-1850 2000);
DISPLAY INVISIBLE (-1850 2000);
FORCEPROP 1 LAST BODY_TYPE PLUMBING
J 0
(-1850 2050);
DISPLAY 0.872340 (-1850 2050);
PAINT GREEN (-1850 2050);
DISPLAY INVISIBLE (-1850 2050);
FORCEPROP 1 LAST HDL_TAP TRUE
J 0
(-1525 1875);
DISPLAY 0.872340 (-1525 1875);
DISPLAY INVISIBLE (-1525 1875);
FORCEPROP 1 LAST PATH I48
J 0
(-1852 2000);
DISPLAY 0.872340 (-1852 2000);
PAINT GREEN (-1852 2000);
DISPLAY INVISIBLE (-1852 2000);
FORCEADD TAP..1
(-1850 2200);
FORCEPROP 3 LASTPIN (-1900 2200) SIG_NAME P5E_CPU0_P1_TX_BUF_C_DP<0>
J 0
(-1890 2210);
DISPLAY 0.659574 (-1890 2210);
PAINT MONO (-1890 2210);
DISPLAY INVISIBLE (-1890 2210);
FORCEPROP 1 LASTPIN (-1900 2200) BN 0
J 0
(-1912 2208);
DISPLAY 0.680851 (-1912 2208);
PAINT GREEN (-1912 2208);
FORCEPROP 2 LAST CDS_LIB standard
J 0
(-1850 2200);
DISPLAY INVISIBLE (-1850 2200);
FORCEPROP 1 LAST BODY_TYPE PLUMBING
J 0
(-1850 2250);
DISPLAY 0.872340 (-1850 2250);
PAINT GREEN (-1850 2250);
DISPLAY INVISIBLE (-1850 2250);
FORCEPROP 1 LAST HDL_TAP TRUE
J 0
(-1525 2075);
DISPLAY 0.872340 (-1525 2075);
DISPLAY INVISIBLE (-1525 2075);
FORCEPROP 1 LAST PATH I49
J 0
(-1852 2200);
DISPLAY 0.872340 (-1852 2200);
PAINT GREEN (-1852 2200);
DISPLAY INVISIBLE (-1852 2200);
FORCEADD TAP..1
R 2
(-3375 1150);
FORCEPROP 3 LASTPIN (-3325 1150) SIG_NAME P5E_CPU0_P1_TX_BUF_DN<5>
J 0
(-3315 1160);
DISPLAY 0.659574 (-3315 1160);
PAINT MONO (-3315 1160);
DISPLAY INVISIBLE (-3315 1160);
FORCEPROP 1 LASTPIN (-3325 1150) BN 5
J 2
(-3313 1158);
DISPLAY 0.680851 (-3313 1158);
PAINT GREEN (-3313 1158);
FORCEPROP 2 LAST CDS_LIB standard
J 0
(-3375 1150);
DISPLAY INVISIBLE (-3375 1150);
FORCEPROP 1 LAST BODY_TYPE PLUMBING
J 2
(-3375 1200);
DISPLAY 0.872340 (-3375 1200);
PAINT GREEN (-3375 1200);
DISPLAY INVISIBLE (-3375 1200);
FORCEPROP 1 LAST HDL_TAP TRUE
J 2
(-3700 1025);
DISPLAY 0.872340 (-3700 1025);
DISPLAY INVISIBLE (-3700 1025);
FORCEPROP 1 LAST PATH I5
J 2
(-3373 1150);
DISPLAY 0.872340 (-3373 1150);
PAINT GREEN (-3373 1150);
DISPLAY INVISIBLE (-3373 1150);
FORCEADD TAP..1
(-1650 1950);
FORCEPROP 3 LASTPIN (-1700 1950) SIG_NAME P5E_CPU0_P1_TX_BUF_C_DN<1>
J 0
(-1690 1960);
DISPLAY 0.659574 (-1690 1960);
PAINT MONO (-1690 1960);
DISPLAY INVISIBLE (-1690 1960);
FORCEPROP 1 LASTPIN (-1700 1950) BN 1
J 0
(-1712 1958);
DISPLAY 0.680851 (-1712 1958);
PAINT GREEN (-1712 1958);
FORCEPROP 2 LAST CDS_LIB standard
J 0
(-1650 1950);
DISPLAY INVISIBLE (-1650 1950);
FORCEPROP 1 LAST BODY_TYPE PLUMBING
J 0
(-1650 2000);
DISPLAY 0.872340 (-1650 2000);
PAINT GREEN (-1650 2000);
DISPLAY INVISIBLE (-1650 2000);
FORCEPROP 1 LAST HDL_TAP TRUE
J 0
(-1325 1825);
DISPLAY 0.872340 (-1325 1825);
DISPLAY INVISIBLE (-1325 1825);
FORCEPROP 1 LAST PATH I50
J 0
(-1652 1950);
DISPLAY 0.872340 (-1652 1950);
PAINT GREEN (-1652 1950);
DISPLAY INVISIBLE (-1652 1950);
FORCEADD TAP..1
(-1650 2150);
FORCEPROP 3 LASTPIN (-1700 2150) SIG_NAME P5E_CPU0_P1_TX_BUF_C_DN<0>
J 0
(-1690 2160);
DISPLAY 0.659574 (-1690 2160);
PAINT MONO (-1690 2160);
DISPLAY INVISIBLE (-1690 2160);
FORCEPROP 1 LASTPIN (-1700 2150) BN 0
J 0
(-1712 2158);
DISPLAY 0.680851 (-1712 2158);
PAINT GREEN (-1712 2158);
FORCEPROP 2 LAST CDS_LIB standard
J 0
(-1650 2150);
DISPLAY INVISIBLE (-1650 2150);
FORCEPROP 1 LAST BODY_TYPE PLUMBING
J 0
(-1650 2200);
DISPLAY 0.872340 (-1650 2200);
PAINT GREEN (-1650 2200);
DISPLAY INVISIBLE (-1650 2200);
FORCEPROP 1 LAST HDL_TAP TRUE
J 0
(-1325 2025);
DISPLAY 0.872340 (-1325 2025);
DISPLAY INVISIBLE (-1325 2025);
FORCEPROP 1 LAST PATH I51
J 0
(-1652 2150);
DISPLAY 0.872340 (-1652 2150);
PAINT GREEN (-1652 2150);
DISPLAY INVISIBLE (-1652 2150);
FORCEADD TAP..1
(-6850 3275);
FORCEPROP 3 LASTPIN (-6900 3275) SIG_NAME P5E_CPU0_P1_TX_BUF_DN<8>
J 0
(-6890 3285);
DISPLAY 0.659574 (-6890 3285);
PAINT MONO (-6890 3285);
DISPLAY INVISIBLE (-6890 3285);
FORCEPROP 1 LASTPIN (-6900 3275) BN 8
J 0
(-6912 3283);
DISPLAY 0.680851 (-6912 3283);
PAINT GREEN (-6912 3283);
FORCEPROP 2 LAST CDS_LIB standard
J 0
(-6850 3275);
DISPLAY INVISIBLE (-6850 3275);
FORCEPROP 1 LAST BODY_TYPE PLUMBING
J 0
(-6850 3325);
DISPLAY 0.872340 (-6850 3325);
PAINT GREEN (-6850 3325);
DISPLAY INVISIBLE (-6850 3325);
FORCEPROP 1 LAST HDL_TAP TRUE
J 0
(-6525 3150);
DISPLAY 0.872340 (-6525 3150);
DISPLAY INVISIBLE (-6525 3150);
FORCEPROP 1 LAST PATH I52
J 0
(-6852 3275);
DISPLAY 0.872340 (-6852 3275);
PAINT GREEN (-6852 3275);
DISPLAY INVISIBLE (-6852 3275);
FORCEADD TAP..1
(-7050 3375);
FORCEPROP 3 LASTPIN (-7100 3375) SIG_NAME P5E_CPU0_P1_TX_BUF_DP<8>
J 0
(-7090 3385);
DISPLAY 0.659574 (-7090 3385);
PAINT MONO (-7090 3385);
DISPLAY INVISIBLE (-7090 3385);
FORCEPROP 1 LASTPIN (-7100 3375) BN 8
J 0
(-7112 3383);
DISPLAY 0.680851 (-7112 3383);
PAINT GREEN (-7112 3383);
FORCEPROP 2 LAST CDS_LIB standard
J 0
(-7050 3375);
DISPLAY INVISIBLE (-7050 3375);
FORCEPROP 1 LAST BODY_TYPE PLUMBING
J 0
(-7050 3425);
DISPLAY 0.872340 (-7050 3425);
PAINT GREEN (-7050 3425);
DISPLAY INVISIBLE (-7050 3425);
FORCEPROP 1 LAST HDL_TAP TRUE
J 0
(-6725 3250);
DISPLAY 0.872340 (-6725 3250);
DISPLAY INVISIBLE (-6725 3250);
FORCEPROP 1 LAST PATH I53
J 0
(-7052 3375);
DISPLAY 0.872340 (-7052 3375);
PAINT GREEN (-7052 3375);
DISPLAY INVISIBLE (-7052 3375);
FORCEADD TAP..1
(-6850 3625);
FORCEPROP 3 LASTPIN (-6900 3625) SIG_NAME P5E_CPU0_P1_TX_BUF_DN<9>
J 0
(-6890 3635);
DISPLAY 0.659574 (-6890 3635);
PAINT MONO (-6890 3635);
DISPLAY INVISIBLE (-6890 3635);
FORCEPROP 1 LASTPIN (-6900 3625) BN 9
J 0
(-6912 3633);
DISPLAY 0.680851 (-6912 3633);
PAINT GREEN (-6912 3633);
FORCEPROP 2 LAST CDS_LIB standard
J 0
(-6850 3625);
DISPLAY INVISIBLE (-6850 3625);
FORCEPROP 1 LAST BODY_TYPE PLUMBING
J 0
(-6850 3675);
DISPLAY 0.872340 (-6850 3675);
PAINT GREEN (-6850 3675);
DISPLAY INVISIBLE (-6850 3675);
FORCEPROP 1 LAST HDL_TAP TRUE
J 0
(-6525 3500);
DISPLAY 0.872340 (-6525 3500);
DISPLAY INVISIBLE (-6525 3500);
FORCEPROP 1 LAST PATH I54
J 0
(-6852 3625);
DISPLAY 0.872340 (-6852 3625);
PAINT GREEN (-6852 3625);
DISPLAY INVISIBLE (-6852 3625);
FORCEADD TAP..1
(-7050 3725);
FORCEPROP 3 LASTPIN (-7100 3725) SIG_NAME P5E_CPU0_P1_TX_BUF_DP<9>
J 0
(-7090 3735);
DISPLAY 0.659574 (-7090 3735);
PAINT MONO (-7090 3735);
DISPLAY INVISIBLE (-7090 3735);
FORCEPROP 1 LASTPIN (-7100 3725) BN 9
J 0
(-7112 3733);
DISPLAY 0.680851 (-7112 3733);
PAINT GREEN (-7112 3733);
FORCEPROP 2 LAST CDS_LIB standard
J 0
(-7050 3725);
DISPLAY INVISIBLE (-7050 3725);
FORCEPROP 1 LAST BODY_TYPE PLUMBING
J 0
(-7050 3775);
DISPLAY 0.872340 (-7050 3775);
PAINT GREEN (-7050 3775);
DISPLAY INVISIBLE (-7050 3775);
FORCEPROP 1 LAST HDL_TAP TRUE
J 0
(-6725 3600);
DISPLAY 0.872340 (-6725 3600);
DISPLAY INVISIBLE (-6725 3600);
FORCEPROP 1 LAST PATH I55
J 0
(-7052 3725);
DISPLAY 0.872340 (-7052 3725);
PAINT GREEN (-7052 3725);
DISPLAY INVISIBLE (-7052 3725);
FORCEADD OFFPAGE..2
(-650 2175);
FORCEPROP 2 LAST $XR0 118 
J 0
(-461 2175);
DISPLAY 0.638298 (-461 2175);
PAINT MONO (-461 2175);
FORCEPROP 2 LAST CDS_LIB standard
J 0
(-650 2175);
DISPLAY INVISIBLE (-650 2175);
FORCEPROP 1 LAST OFFPAGE TRUE
J 0
(-325 2050);
DISPLAY 0.872340 (-325 2050);
DISPLAY INVISIBLE (-325 2050);
FORCEPROP 1 LAST COMMENT_BODY TRUE
J 0
(-695 2080);
DISPLAY 0.872340 (-695 2080);
PAINT GREEN (-695 2080);
DISPLAY INVISIBLE (-695 2080);
FORCEPROP 2 LAST PATH I56
J 0
(-450 2225);
DISPLAY 0.680851 (-450 2225);
DISPLAY INVISIBLE (-450 2225);
FORCEADD OFFPAGE..2
(-650 2225);
FORCEPROP 2 LAST $XR0 118 
J 0
(-461 2225);
DISPLAY 0.638298 (-461 2225);
PAINT MONO (-461 2225);
FORCEPROP 2 LAST CDS_LIB standard
J 0
(-650 2225);
DISPLAY INVISIBLE (-650 2225);
FORCEPROP 1 LAST OFFPAGE TRUE
J 0
(-325 2100);
DISPLAY 0.872340 (-325 2100);
DISPLAY INVISIBLE (-325 2100);
FORCEPROP 1 LAST COMMENT_BODY TRUE
J 0
(-695 2130);
DISPLAY 0.872340 (-695 2130);
PAINT GREEN (-695 2130);
DISPLAY INVISIBLE (-695 2130);
FORCEPROP 2 LAST PATH I57
J 0
(-450 2275);
DISPLAY 0.680851 (-450 2275);
DISPLAY INVISIBLE (-450 2275);
FORCEADD OFFPAGE..1
(-8850 2225);
FORCEPROP 2 LAST $XR0 287 
J 0
(-9102 2225);
DISPLAY 0.638298 (-9102 2225);
PAINT MONO (-9102 2225);
FORCEPROP 2 LAST CDS_LIB standard
J 0
(-8850 2225);
DISPLAY INVISIBLE (-8850 2225);
FORCEPROP 1 LAST OFFPAGE TRUE
J 0
(-8525 2100);
DISPLAY 0.872340 (-8525 2100);
DISPLAY INVISIBLE (-8525 2100);
FORCEPROP 1 LAST COMMENT_BODY TRUE
J 0
(-8725 2125);
DISPLAY 0.872340 (-8725 2125);
PAINT GREEN (-8725 2125);
DISPLAY INVISIBLE (-8725 2125);
FORCEPROP 2 LAST PATH I58
J 0
(-9100 2275);
DISPLAY 0.680851 (-9100 2275);
DISPLAY INVISIBLE (-9100 2275);
FORCEADD OFFPAGE..1
(-8850 2175);
FORCEPROP 2 LAST $XR0 287 
J 0
(-9102 2175);
DISPLAY 0.638298 (-9102 2175);
PAINT MONO (-9102 2175);
FORCEPROP 2 LAST CDS_LIB standard
J 0
(-8850 2175);
DISPLAY INVISIBLE (-8850 2175);
FORCEPROP 1 LAST OFFPAGE TRUE
J 0
(-8525 2050);
DISPLAY 0.872340 (-8525 2050);
DISPLAY INVISIBLE (-8525 2050);
FORCEPROP 1 LAST COMMENT_BODY TRUE
J 0
(-8725 2075);
DISPLAY 0.872340 (-8725 2075);
PAINT GREEN (-8725 2075);
DISPLAY INVISIBLE (-8725 2075);
FORCEPROP 2 LAST PATH I59
J 0
(-9100 2225);
DISPLAY 0.680851 (-9100 2225);
DISPLAY INVISIBLE (-9100 2225);
FORCEADD TAP..1
R 2
(-3375 1350);
FORCEPROP 3 LASTPIN (-3325 1350) SIG_NAME P5E_CPU0_P1_TX_BUF_DN<4>
J 0
(-3315 1360);
DISPLAY 0.659574 (-3315 1360);
PAINT MONO (-3315 1360);
DISPLAY INVISIBLE (-3315 1360);
FORCEPROP 1 LASTPIN (-3325 1350) BN 4
J 2
(-3313 1358);
DISPLAY 0.680851 (-3313 1358);
PAINT GREEN (-3313 1358);
FORCEPROP 2 LAST CDS_LIB standard
J 0
(-3375 1350);
DISPLAY INVISIBLE (-3375 1350);
FORCEPROP 1 LAST BODY_TYPE PLUMBING
J 2
(-3375 1400);
DISPLAY 0.872340 (-3375 1400);
PAINT GREEN (-3375 1400);
DISPLAY INVISIBLE (-3375 1400);
FORCEPROP 1 LAST HDL_TAP TRUE
J 2
(-3700 1225);
DISPLAY 0.872340 (-3700 1225);
DISPLAY INVISIBLE (-3700 1225);
FORCEPROP 1 LAST PATH I6
J 2
(-3373 1350);
DISPLAY 0.872340 (-3373 1350);
PAINT GREEN (-3373 1350);
DISPLAY INVISIBLE (-3373 1350);
FORCEADD TAP..1
(-6850 3975);
FORCEPROP 3 LASTPIN (-6900 3975) SIG_NAME P5E_CPU0_P1_TX_BUF_DN<10>
J 0
(-6890 3985);
DISPLAY 0.659574 (-6890 3985);
PAINT MONO (-6890 3985);
DISPLAY INVISIBLE (-6890 3985);
FORCEPROP 1 LASTPIN (-6900 3975) BN 10
J 0
(-6912 3983);
DISPLAY 0.680851 (-6912 3983);
PAINT GREEN (-6912 3983);
FORCEPROP 2 LAST CDS_LIB standard
J 0
(-6850 3975);
DISPLAY INVISIBLE (-6850 3975);
FORCEPROP 1 LAST BODY_TYPE PLUMBING
J 0
(-6850 4025);
DISPLAY 0.872340 (-6850 4025);
PAINT GREEN (-6850 4025);
DISPLAY INVISIBLE (-6850 4025);
FORCEPROP 1 LAST HDL_TAP TRUE
J 0
(-6525 3850);
DISPLAY 0.872340 (-6525 3850);
DISPLAY INVISIBLE (-6525 3850);
FORCEPROP 1 LAST PATH I60
J 0
(-6852 3975);
DISPLAY 0.872340 (-6852 3975);
PAINT GREEN (-6852 3975);
DISPLAY INVISIBLE (-6852 3975);
FORCEADD TAP..1
(-7050 4075);
FORCEPROP 3 LASTPIN (-7100 4075) SIG_NAME P5E_CPU0_P1_TX_BUF_DP<10>
J 0
(-7090 4085);
DISPLAY 0.659574 (-7090 4085);
PAINT MONO (-7090 4085);
DISPLAY INVISIBLE (-7090 4085);
FORCEPROP 1 LASTPIN (-7100 4075) BN 10
J 0
(-7112 4083);
DISPLAY 0.680851 (-7112 4083);
PAINT GREEN (-7112 4083);
FORCEPROP 2 LAST CDS_LIB standard
J 0
(-7050 4075);
DISPLAY INVISIBLE (-7050 4075);
FORCEPROP 1 LAST BODY_TYPE PLUMBING
J 0
(-7050 4125);
DISPLAY 0.872340 (-7050 4125);
PAINT GREEN (-7050 4125);
DISPLAY INVISIBLE (-7050 4125);
FORCEPROP 1 LAST HDL_TAP TRUE
J 0
(-6725 3950);
DISPLAY 0.872340 (-6725 3950);
DISPLAY INVISIBLE (-6725 3950);
FORCEPROP 1 LAST PATH I61
J 0
(-7052 4075);
DISPLAY 0.872340 (-7052 4075);
PAINT GREEN (-7052 4075);
DISPLAY INVISIBLE (-7052 4075);
FORCEADD TAP..1
(-6850 4325);
FORCEPROP 3 LASTPIN (-6900 4325) SIG_NAME P5E_CPU0_P1_TX_BUF_DN<11>
J 0
(-6890 4335);
DISPLAY 0.659574 (-6890 4335);
PAINT MONO (-6890 4335);
DISPLAY INVISIBLE (-6890 4335);
FORCEPROP 1 LASTPIN (-6900 4325) BN 11
J 0
(-6912 4333);
DISPLAY 0.680851 (-6912 4333);
PAINT GREEN (-6912 4333);
FORCEPROP 2 LAST CDS_LIB standard
J 0
(-6850 4325);
DISPLAY INVISIBLE (-6850 4325);
FORCEPROP 1 LAST BODY_TYPE PLUMBING
J 0
(-6850 4375);
DISPLAY 0.872340 (-6850 4375);
PAINT GREEN (-6850 4375);
DISPLAY INVISIBLE (-6850 4375);
FORCEPROP 1 LAST HDL_TAP TRUE
J 0
(-6525 4200);
DISPLAY 0.872340 (-6525 4200);
DISPLAY INVISIBLE (-6525 4200);
FORCEPROP 1 LAST PATH I62
J 0
(-6852 4325);
DISPLAY 0.872340 (-6852 4325);
PAINT GREEN (-6852 4325);
DISPLAY INVISIBLE (-6852 4325);
FORCEADD TAP..1
(-7050 4425);
FORCEPROP 3 LASTPIN (-7100 4425) SIG_NAME P5E_CPU0_P1_TX_BUF_DP<11>
J 0
(-7090 4435);
DISPLAY 0.659574 (-7090 4435);
PAINT MONO (-7090 4435);
DISPLAY INVISIBLE (-7090 4435);
FORCEPROP 1 LASTPIN (-7100 4425) BN 11
J 0
(-7112 4433);
DISPLAY 0.680851 (-7112 4433);
PAINT GREEN (-7112 4433);
FORCEPROP 2 LAST CDS_LIB standard
J 0
(-7050 4425);
DISPLAY INVISIBLE (-7050 4425);
FORCEPROP 1 LAST BODY_TYPE PLUMBING
J 0
(-7050 4475);
DISPLAY 0.872340 (-7050 4475);
PAINT GREEN (-7050 4475);
DISPLAY INVISIBLE (-7050 4475);
FORCEPROP 1 LAST HDL_TAP TRUE
J 0
(-6725 4300);
DISPLAY 0.872340 (-6725 4300);
DISPLAY INVISIBLE (-6725 4300);
FORCEPROP 1 LAST PATH I63
J 0
(-7052 4425);
DISPLAY 0.872340 (-7052 4425);
PAINT GREEN (-7052 4425);
DISPLAY INVISIBLE (-7052 4425);
FORCEADD TAP..1
(-7050 4775);
FORCEPROP 3 LASTPIN (-7100 4775) SIG_NAME P5E_CPU0_P1_TX_BUF_DP<12>
J 0
(-7090 4785);
DISPLAY 0.659574 (-7090 4785);
PAINT MONO (-7090 4785);
DISPLAY INVISIBLE (-7090 4785);
FORCEPROP 1 LASTPIN (-7100 4775) BN 12
J 0
(-7112 4783);
DISPLAY 0.680851 (-7112 4783);
PAINT GREEN (-7112 4783);
FORCEPROP 2 LAST CDS_LIB standard
J 0
(-7050 4775);
DISPLAY INVISIBLE (-7050 4775);
FORCEPROP 1 LAST BODY_TYPE PLUMBING
J 0
(-7050 4825);
DISPLAY 0.872340 (-7050 4825);
PAINT GREEN (-7050 4825);
DISPLAY INVISIBLE (-7050 4825);
FORCEPROP 1 LAST HDL_TAP TRUE
J 0
(-6725 4650);
DISPLAY 0.872340 (-6725 4650);
DISPLAY INVISIBLE (-6725 4650);
FORCEPROP 1 LAST PATH I64
J 0
(-7052 4775);
DISPLAY 0.872340 (-7052 4775);
PAINT GREEN (-7052 4775);
DISPLAY INVISIBLE (-7052 4775);
FORCEADD TAP..1
(-6850 4675);
FORCEPROP 3 LASTPIN (-6900 4675) SIG_NAME P5E_CPU0_P1_TX_BUF_DN<12>
J 0
(-6890 4685);
DISPLAY 0.659574 (-6890 4685);
PAINT MONO (-6890 4685);
DISPLAY INVISIBLE (-6890 4685);
FORCEPROP 1 LASTPIN (-6900 4675) BN 12
J 0
(-6912 4683);
DISPLAY 0.680851 (-6912 4683);
PAINT GREEN (-6912 4683);
FORCEPROP 2 LAST CDS_LIB standard
J 0
(-6850 4675);
DISPLAY INVISIBLE (-6850 4675);
FORCEPROP 1 LAST BODY_TYPE PLUMBING
J 0
(-6850 4725);
DISPLAY 0.872340 (-6850 4725);
PAINT GREEN (-6850 4725);
DISPLAY INVISIBLE (-6850 4725);
FORCEPROP 1 LAST HDL_TAP TRUE
J 0
(-6525 4550);
DISPLAY 0.872340 (-6525 4550);
DISPLAY INVISIBLE (-6525 4550);
FORCEPROP 1 LAST PATH I65
J 0
(-6852 4675);
DISPLAY 0.872340 (-6852 4675);
PAINT GREEN (-6852 4675);
DISPLAY INVISIBLE (-6852 4675);
FORCEADD TAP..1
(-6850 5025);
FORCEPROP 3 LASTPIN (-6900 5025) SIG_NAME P5E_CPU0_P1_TX_BUF_DN<13>
J 0
(-6890 5035);
DISPLAY 0.659574 (-6890 5035);
PAINT MONO (-6890 5035);
DISPLAY INVISIBLE (-6890 5035);
FORCEPROP 1 LASTPIN (-6900 5025) BN 13
J 0
(-6912 5033);
DISPLAY 0.680851 (-6912 5033);
PAINT GREEN (-6912 5033);
FORCEPROP 2 LAST CDS_LIB standard
J 0
(-6850 5025);
DISPLAY INVISIBLE (-6850 5025);
FORCEPROP 1 LAST BODY_TYPE PLUMBING
J 0
(-6850 5075);
DISPLAY 0.872340 (-6850 5075);
PAINT GREEN (-6850 5075);
DISPLAY INVISIBLE (-6850 5075);
FORCEPROP 1 LAST HDL_TAP TRUE
J 0
(-6525 4900);
DISPLAY 0.872340 (-6525 4900);
DISPLAY INVISIBLE (-6525 4900);
FORCEPROP 1 LAST PATH I66
J 0
(-6852 5025);
DISPLAY 0.872340 (-6852 5025);
PAINT GREEN (-6852 5025);
DISPLAY INVISIBLE (-6852 5025);
FORCEADD TAP..1
(-7050 5125);
FORCEPROP 3 LASTPIN (-7100 5125) SIG_NAME P5E_CPU0_P1_TX_BUF_DP<13>
J 0
(-7090 5135);
DISPLAY 0.659574 (-7090 5135);
PAINT MONO (-7090 5135);
DISPLAY INVISIBLE (-7090 5135);
FORCEPROP 1 LASTPIN (-7100 5125) BN 13
J 0
(-7112 5133);
DISPLAY 0.680851 (-7112 5133);
PAINT GREEN (-7112 5133);
FORCEPROP 2 LAST CDS_LIB standard
J 0
(-7050 5125);
DISPLAY INVISIBLE (-7050 5125);
FORCEPROP 1 LAST BODY_TYPE PLUMBING
J 0
(-7050 5175);
DISPLAY 0.872340 (-7050 5175);
PAINT GREEN (-7050 5175);
DISPLAY INVISIBLE (-7050 5175);
FORCEPROP 1 LAST HDL_TAP TRUE
J 0
(-6725 5000);
DISPLAY 0.872340 (-6725 5000);
DISPLAY INVISIBLE (-6725 5000);
FORCEPROP 1 LAST PATH I67
J 0
(-7052 5125);
DISPLAY 0.872340 (-7052 5125);
PAINT GREEN (-7052 5125);
DISPLAY INVISIBLE (-7052 5125);
FORCEADD TAP..1
(-6850 5375);
FORCEPROP 3 LASTPIN (-6900 5375) SIG_NAME P5E_CPU0_P1_TX_BUF_DN<14>
J 0
(-6890 5385);
DISPLAY 0.659574 (-6890 5385);
PAINT MONO (-6890 5385);
DISPLAY INVISIBLE (-6890 5385);
FORCEPROP 1 LASTPIN (-6900 5375) BN 14
J 0
(-6912 5383);
DISPLAY 0.680851 (-6912 5383);
PAINT GREEN (-6912 5383);
FORCEPROP 2 LAST CDS_LIB standard
J 0
(-6850 5375);
DISPLAY INVISIBLE (-6850 5375);
FORCEPROP 1 LAST BODY_TYPE PLUMBING
J 0
(-6850 5425);
DISPLAY 0.872340 (-6850 5425);
PAINT GREEN (-6850 5425);
DISPLAY INVISIBLE (-6850 5425);
FORCEPROP 1 LAST HDL_TAP TRUE
J 0
(-6525 5250);
DISPLAY 0.872340 (-6525 5250);
DISPLAY INVISIBLE (-6525 5250);
FORCEPROP 1 LAST PATH I68
J 0
(-6852 5375);
DISPLAY 0.872340 (-6852 5375);
PAINT GREEN (-6852 5375);
DISPLAY INVISIBLE (-6852 5375);
FORCEADD TAP..1
(-7050 5475);
FORCEPROP 3 LASTPIN (-7100 5475) SIG_NAME P5E_CPU0_P1_TX_BUF_DP<14>
J 0
(-7090 5485);
DISPLAY 0.659574 (-7090 5485);
PAINT MONO (-7090 5485);
DISPLAY INVISIBLE (-7090 5485);
FORCEPROP 1 LASTPIN (-7100 5475) BN 14
J 0
(-7112 5483);
DISPLAY 0.680851 (-7112 5483);
PAINT GREEN (-7112 5483);
FORCEPROP 2 LAST CDS_LIB standard
J 0
(-7050 5475);
DISPLAY INVISIBLE (-7050 5475);
FORCEPROP 1 LAST BODY_TYPE PLUMBING
J 0
(-7050 5525);
DISPLAY 0.872340 (-7050 5525);
PAINT GREEN (-7050 5525);
DISPLAY INVISIBLE (-7050 5525);
FORCEPROP 1 LAST HDL_TAP TRUE
J 0
(-6725 5350);
DISPLAY 0.872340 (-6725 5350);
DISPLAY INVISIBLE (-6725 5350);
FORCEPROP 1 LAST PATH I69
J 0
(-7052 5475);
DISPLAY 0.872340 (-7052 5475);
PAINT GREEN (-7052 5475);
DISPLAY INVISIBLE (-7052 5475);
FORCEADD TAP..1
R 2
(-3375 1550);
FORCEPROP 3 LASTPIN (-3325 1550) SIG_NAME P5E_CPU0_P1_TX_BUF_DN<3>
J 0
(-3315 1560);
DISPLAY 0.659574 (-3315 1560);
PAINT MONO (-3315 1560);
DISPLAY INVISIBLE (-3315 1560);
FORCEPROP 1 LASTPIN (-3325 1550) BN 3
J 2
(-3313 1558);
DISPLAY 0.680851 (-3313 1558);
PAINT GREEN (-3313 1558);
FORCEPROP 2 LAST CDS_LIB standard
J 0
(-3375 1550);
DISPLAY INVISIBLE (-3375 1550);
FORCEPROP 1 LAST BODY_TYPE PLUMBING
J 2
(-3375 1600);
DISPLAY 0.872340 (-3375 1600);
PAINT GREEN (-3375 1600);
DISPLAY INVISIBLE (-3375 1600);
FORCEPROP 1 LAST HDL_TAP TRUE
J 2
(-3700 1425);
DISPLAY 0.872340 (-3700 1425);
DISPLAY INVISIBLE (-3700 1425);
FORCEPROP 1 LAST PATH I7
J 2
(-3373 1550);
DISPLAY 0.872340 (-3373 1550);
PAINT GREEN (-3373 1550);
DISPLAY INVISIBLE (-3373 1550);
FORCEADD TAP..1
(-6850 5725);
FORCEPROP 3 LASTPIN (-6900 5725) SIG_NAME P5E_CPU0_P1_TX_BUF_DN<15>
J 0
(-6890 5735);
DISPLAY 0.659574 (-6890 5735);
PAINT MONO (-6890 5735);
DISPLAY INVISIBLE (-6890 5735);
FORCEPROP 1 LASTPIN (-6900 5725) BN 15
J 0
(-6912 5733);
DISPLAY 0.680851 (-6912 5733);
PAINT GREEN (-6912 5733);
FORCEPROP 2 LAST CDS_LIB standard
J 0
(-6850 5725);
DISPLAY INVISIBLE (-6850 5725);
FORCEPROP 1 LAST BODY_TYPE PLUMBING
J 0
(-6850 5775);
DISPLAY 0.872340 (-6850 5775);
PAINT GREEN (-6850 5775);
DISPLAY INVISIBLE (-6850 5775);
FORCEPROP 1 LAST HDL_TAP TRUE
J 0
(-6525 5600);
DISPLAY 0.872340 (-6525 5600);
DISPLAY INVISIBLE (-6525 5600);
FORCEPROP 1 LAST PATH I70
J 0
(-6852 5725);
DISPLAY 0.872340 (-6852 5725);
PAINT GREEN (-6852 5725);
DISPLAY INVISIBLE (-6852 5725);
FORCEADD TAP..1
(-7050 5825);
FORCEPROP 3 LASTPIN (-7100 5825) SIG_NAME P5E_CPU0_P1_TX_BUF_DP<15>
J 0
(-7090 5835);
DISPLAY 0.659574 (-7090 5835);
PAINT MONO (-7090 5835);
DISPLAY INVISIBLE (-7090 5835);
FORCEPROP 1 LASTPIN (-7100 5825) BN 15
J 0
(-7112 5833);
DISPLAY 0.680851 (-7112 5833);
PAINT GREEN (-7112 5833);
FORCEPROP 2 LAST CDS_LIB standard
J 0
(-7050 5825);
DISPLAY INVISIBLE (-7050 5825);
FORCEPROP 1 LAST BODY_TYPE PLUMBING
J 0
(-7050 5875);
DISPLAY 0.872340 (-7050 5875);
PAINT GREEN (-7050 5875);
DISPLAY INVISIBLE (-7050 5875);
FORCEPROP 1 LAST HDL_TAP TRUE
J 0
(-6725 5700);
DISPLAY 0.872340 (-6725 5700);
DISPLAY INVISIBLE (-6725 5700);
FORCEPROP 1 LAST PATH I71
J 0
(-7052 5825);
DISPLAY 0.872340 (-7052 5825);
PAINT GREEN (-7052 5825);
DISPLAY INVISIBLE (-7052 5825);
FORCEADD OFFPAGE..5
R 2
(-5875 5750);
FORCEPROP 2 LAST $XR0 287 
J 0
(-5686 5750);
DISPLAY 0.638298 (-5686 5750);
PAINT MONO (-5686 5750);
FORCEPROP 2 LAST CDS_LIB standard
J 0
(-5875 5750);
DISPLAY INVISIBLE (-5875 5750);
FORCEPROP 1 LAST OFFPAGE TRUE
J 2
(-6200 5625);
DISPLAY 0.872340 (-6200 5625);
PAINT GREEN (-6200 5625);
DISPLAY INVISIBLE (-6200 5625);
FORCEPROP 1 LAST COMMENT_BODY TRUE
J 2
(-5975 5675);
DISPLAY 0.872340 (-5975 5675);
PAINT GREEN (-5975 5675);
DISPLAY INVISIBLE (-5975 5675);
FORCEPROP 2 LAST PATH I72
J 0
(-5700 5825);
DISPLAY 0.680851 (-5700 5825);
DISPLAY INVISIBLE (-5700 5825);
FORCEADD OFFPAGE..5
R 2
(-5850 5850);
FORCEPROP 2 LAST $XR0 287 
J 0
(-5661 5850);
DISPLAY 0.638298 (-5661 5850);
PAINT MONO (-5661 5850);
FORCEPROP 2 LAST CDS_LIB standard
J 0
(-5850 5850);
DISPLAY INVISIBLE (-5850 5850);
FORCEPROP 1 LAST OFFPAGE TRUE
J 2
(-6175 5725);
DISPLAY 0.872340 (-6175 5725);
PAINT GREEN (-6175 5725);
DISPLAY INVISIBLE (-6175 5725);
FORCEPROP 1 LAST COMMENT_BODY TRUE
J 2
(-5950 5775);
DISPLAY 0.872340 (-5950 5775);
PAINT GREEN (-5950 5775);
DISPLAY INVISIBLE (-5950 5775);
FORCEPROP 2 LAST PATH I73
J 0
(-5675 5925);
DISPLAY 0.680851 (-5675 5925);
DISPLAY INVISIBLE (-5675 5925);
FORCEADD TAP..1
R 2
(-7900 750);
FORCEPROP 3 LASTPIN (-7850 750) SIG_NAME P5E_CPU0_P1_TX_BUF_DN<15>
J 0
(-7840 760);
DISPLAY 0.659574 (-7840 760);
PAINT MONO (-7840 760);
DISPLAY INVISIBLE (-7840 760);
FORCEPROP 1 LASTPIN (-7850 750) BN 15
J 2
(-7838 758);
DISPLAY 0.680851 (-7838 758);
PAINT GREEN (-7838 758);
FORCEPROP 2 LAST CDS_LIB standard
J 0
(-7900 750);
DISPLAY INVISIBLE (-7900 750);
FORCEPROP 1 LAST BODY_TYPE PLUMBING
J 2
(-7900 800);
DISPLAY 0.872340 (-7900 800);
PAINT GREEN (-7900 800);
DISPLAY INVISIBLE (-7900 800);
FORCEPROP 1 LAST HDL_TAP TRUE
J 2
(-8225 625);
DISPLAY 0.872340 (-8225 625);
DISPLAY INVISIBLE (-8225 625);
FORCEPROP 1 LAST PATH I74
J 2
(-7898 750);
DISPLAY 0.872340 (-7898 750);
PAINT GREEN (-7898 750);
DISPLAY INVISIBLE (-7898 750);
FORCEADD TAP..1
R 2
(-7650 800);
FORCEPROP 3 LASTPIN (-7600 800) SIG_NAME P5E_CPU0_P1_TX_BUF_DP<15>
J 0
(-7590 810);
DISPLAY 0.659574 (-7590 810);
PAINT MONO (-7590 810);
DISPLAY INVISIBLE (-7590 810);
FORCEPROP 1 LASTPIN (-7600 800) BN 15
J 2
(-7588 808);
DISPLAY 0.680851 (-7588 808);
PAINT GREEN (-7588 808);
FORCEPROP 2 LAST CDS_LIB standard
J 0
(-7650 800);
DISPLAY INVISIBLE (-7650 800);
FORCEPROP 1 LAST BODY_TYPE PLUMBING
J 2
(-7650 850);
DISPLAY 0.872340 (-7650 850);
PAINT GREEN (-7650 850);
DISPLAY INVISIBLE (-7650 850);
FORCEPROP 1 LAST HDL_TAP TRUE
J 2
(-7975 675);
DISPLAY 0.872340 (-7975 675);
DISPLAY INVISIBLE (-7975 675);
FORCEPROP 1 LAST PATH I75
J 2
(-7648 800);
DISPLAY 0.872340 (-7648 800);
PAINT GREEN (-7648 800);
DISPLAY INVISIBLE (-7648 800);
FORCEADD TAP..1
R 2
(-7900 950);
FORCEPROP 3 LASTPIN (-7850 950) SIG_NAME P5E_CPU0_P1_TX_BUF_DN<14>
J 0
(-7840 960);
DISPLAY 0.659574 (-7840 960);
PAINT MONO (-7840 960);
DISPLAY INVISIBLE (-7840 960);
FORCEPROP 1 LASTPIN (-7850 950) BN 14
J 2
(-7838 958);
DISPLAY 0.680851 (-7838 958);
PAINT GREEN (-7838 958);
FORCEPROP 2 LAST CDS_LIB standard
J 0
(-7900 950);
DISPLAY INVISIBLE (-7900 950);
FORCEPROP 1 LAST BODY_TYPE PLUMBING
J 2
(-7900 1000);
DISPLAY 0.872340 (-7900 1000);
PAINT GREEN (-7900 1000);
DISPLAY INVISIBLE (-7900 1000);
FORCEPROP 1 LAST HDL_TAP TRUE
J 2
(-8225 825);
DISPLAY 0.872340 (-8225 825);
DISPLAY INVISIBLE (-8225 825);
FORCEPROP 1 LAST PATH I76
J 2
(-7898 950);
DISPLAY 0.872340 (-7898 950);
PAINT GREEN (-7898 950);
DISPLAY INVISIBLE (-7898 950);
FORCEADD TAP..1
R 2
(-7900 1150);
FORCEPROP 3 LASTPIN (-7850 1150) SIG_NAME P5E_CPU0_P1_TX_BUF_DN<13>
J 0
(-7840 1160);
DISPLAY 0.659574 (-7840 1160);
PAINT MONO (-7840 1160);
DISPLAY INVISIBLE (-7840 1160);
FORCEPROP 1 LASTPIN (-7850 1150) BN 13
J 2
(-7838 1158);
DISPLAY 0.680851 (-7838 1158);
PAINT GREEN (-7838 1158);
FORCEPROP 2 LAST CDS_LIB standard
J 0
(-7900 1150);
DISPLAY INVISIBLE (-7900 1150);
FORCEPROP 1 LAST BODY_TYPE PLUMBING
J 2
(-7900 1200);
DISPLAY 0.872340 (-7900 1200);
PAINT GREEN (-7900 1200);
DISPLAY INVISIBLE (-7900 1200);
FORCEPROP 1 LAST HDL_TAP TRUE
J 2
(-8225 1025);
DISPLAY 0.872340 (-8225 1025);
DISPLAY INVISIBLE (-8225 1025);
FORCEPROP 1 LAST PATH I77
J 2
(-7898 1150);
DISPLAY 0.872340 (-7898 1150);
PAINT GREEN (-7898 1150);
DISPLAY INVISIBLE (-7898 1150);
FORCEADD TAP..1
R 2
(-7900 1350);
FORCEPROP 3 LASTPIN (-7850 1350) SIG_NAME P5E_CPU0_P1_TX_BUF_DN<12>
J 0
(-7840 1360);
DISPLAY 0.659574 (-7840 1360);
PAINT MONO (-7840 1360);
DISPLAY INVISIBLE (-7840 1360);
FORCEPROP 1 LASTPIN (-7850 1350) BN 12
J 2
(-7838 1358);
DISPLAY 0.680851 (-7838 1358);
PAINT GREEN (-7838 1358);
FORCEPROP 2 LAST CDS_LIB standard
J 0
(-7900 1350);
DISPLAY INVISIBLE (-7900 1350);
FORCEPROP 1 LAST BODY_TYPE PLUMBING
J 2
(-7900 1400);
DISPLAY 0.872340 (-7900 1400);
PAINT GREEN (-7900 1400);
DISPLAY INVISIBLE (-7900 1400);
FORCEPROP 1 LAST HDL_TAP TRUE
J 2
(-8225 1225);
DISPLAY 0.872340 (-8225 1225);
DISPLAY INVISIBLE (-8225 1225);
FORCEPROP 1 LAST PATH I78
J 2
(-7898 1350);
DISPLAY 0.872340 (-7898 1350);
PAINT GREEN (-7898 1350);
DISPLAY INVISIBLE (-7898 1350);
FORCEADD TAP..1
R 2
(-7650 1000);
FORCEPROP 3 LASTPIN (-7600 1000) SIG_NAME P5E_CPU0_P1_TX_BUF_DP<14>
J 0
(-7590 1010);
DISPLAY 0.659574 (-7590 1010);
PAINT MONO (-7590 1010);
DISPLAY INVISIBLE (-7590 1010);
FORCEPROP 1 LASTPIN (-7600 1000) BN 14
J 2
(-7588 1008);
DISPLAY 0.680851 (-7588 1008);
PAINT GREEN (-7588 1008);
FORCEPROP 2 LAST CDS_LIB standard
J 0
(-7650 1000);
DISPLAY INVISIBLE (-7650 1000);
FORCEPROP 1 LAST BODY_TYPE PLUMBING
J 2
(-7650 1050);
DISPLAY 0.872340 (-7650 1050);
PAINT GREEN (-7650 1050);
DISPLAY INVISIBLE (-7650 1050);
FORCEPROP 1 LAST HDL_TAP TRUE
J 2
(-7975 875);
DISPLAY 0.872340 (-7975 875);
DISPLAY INVISIBLE (-7975 875);
FORCEPROP 1 LAST PATH I79
J 2
(-7648 1000);
DISPLAY 0.872340 (-7648 1000);
PAINT GREEN (-7648 1000);
DISPLAY INVISIBLE (-7648 1000);
FORCEADD TAP..1
R 2
(-3375 1750);
FORCEPROP 3 LASTPIN (-3325 1750) SIG_NAME P5E_CPU0_P1_TX_BUF_DN<2>
J 0
(-3315 1760);
DISPLAY 0.659574 (-3315 1760);
PAINT MONO (-3315 1760);
DISPLAY INVISIBLE (-3315 1760);
FORCEPROP 1 LASTPIN (-3325 1750) BN 2
J 2
(-3313 1758);
DISPLAY 0.680851 (-3313 1758);
PAINT GREEN (-3313 1758);
FORCEPROP 2 LAST CDS_LIB standard
J 0
(-3375 1750);
DISPLAY INVISIBLE (-3375 1750);
FORCEPROP 1 LAST BODY_TYPE PLUMBING
J 2
(-3375 1800);
DISPLAY 0.872340 (-3375 1800);
PAINT GREEN (-3375 1800);
DISPLAY INVISIBLE (-3375 1800);
FORCEPROP 1 LAST HDL_TAP TRUE
J 2
(-3700 1625);
DISPLAY 0.872340 (-3700 1625);
DISPLAY INVISIBLE (-3700 1625);
FORCEPROP 1 LAST PATH I8
J 2
(-3373 1750);
DISPLAY 0.872340 (-3373 1750);
PAINT GREEN (-3373 1750);
DISPLAY INVISIBLE (-3373 1750);
FORCEADD TAP..1
R 2
(-7650 1200);
FORCEPROP 3 LASTPIN (-7600 1200) SIG_NAME P5E_CPU0_P1_TX_BUF_DP<13>
J 0
(-7590 1210);
DISPLAY 0.659574 (-7590 1210);
PAINT MONO (-7590 1210);
DISPLAY INVISIBLE (-7590 1210);
FORCEPROP 1 LASTPIN (-7600 1200) BN 13
J 2
(-7588 1208);
DISPLAY 0.680851 (-7588 1208);
PAINT GREEN (-7588 1208);
FORCEPROP 2 LAST CDS_LIB standard
J 0
(-7650 1200);
DISPLAY INVISIBLE (-7650 1200);
FORCEPROP 1 LAST BODY_TYPE PLUMBING
J 2
(-7650 1250);
DISPLAY 0.872340 (-7650 1250);
PAINT GREEN (-7650 1250);
DISPLAY INVISIBLE (-7650 1250);
FORCEPROP 1 LAST HDL_TAP TRUE
J 2
(-7975 1075);
DISPLAY 0.872340 (-7975 1075);
DISPLAY INVISIBLE (-7975 1075);
FORCEPROP 1 LAST PATH I80
J 2
(-7648 1200);
DISPLAY 0.872340 (-7648 1200);
PAINT GREEN (-7648 1200);
DISPLAY INVISIBLE (-7648 1200);
FORCEADD TAP..1
R 2
(-7900 1550);
FORCEPROP 3 LASTPIN (-7850 1550) SIG_NAME P5E_CPU0_P1_TX_BUF_DN<11>
J 0
(-7840 1560);
DISPLAY 0.659574 (-7840 1560);
PAINT MONO (-7840 1560);
DISPLAY INVISIBLE (-7840 1560);
FORCEPROP 1 LASTPIN (-7850 1550) BN 11
J 2
(-7838 1558);
DISPLAY 0.680851 (-7838 1558);
PAINT GREEN (-7838 1558);
FORCEPROP 2 LAST CDS_LIB standard
J 0
(-7900 1550);
DISPLAY INVISIBLE (-7900 1550);
FORCEPROP 1 LAST BODY_TYPE PLUMBING
J 2
(-7900 1600);
DISPLAY 0.872340 (-7900 1600);
PAINT GREEN (-7900 1600);
DISPLAY INVISIBLE (-7900 1600);
FORCEPROP 1 LAST HDL_TAP TRUE
J 2
(-8225 1425);
DISPLAY 0.872340 (-8225 1425);
DISPLAY INVISIBLE (-8225 1425);
FORCEPROP 1 LAST PATH I81
J 2
(-7898 1550);
DISPLAY 0.872340 (-7898 1550);
PAINT GREEN (-7898 1550);
DISPLAY INVISIBLE (-7898 1550);
FORCEADD TAP..1
R 2
(-7900 1750);
FORCEPROP 3 LASTPIN (-7850 1750) SIG_NAME P5E_CPU0_P1_TX_BUF_DN<10>
J 0
(-7840 1760);
DISPLAY 0.659574 (-7840 1760);
PAINT MONO (-7840 1760);
DISPLAY INVISIBLE (-7840 1760);
FORCEPROP 1 LASTPIN (-7850 1750) BN 10
J 2
(-7838 1758);
DISPLAY 0.680851 (-7838 1758);
PAINT GREEN (-7838 1758);
FORCEPROP 2 LAST CDS_LIB standard
J 0
(-7900 1750);
DISPLAY INVISIBLE (-7900 1750);
FORCEPROP 1 LAST BODY_TYPE PLUMBING
J 2
(-7900 1800);
DISPLAY 0.872340 (-7900 1800);
PAINT GREEN (-7900 1800);
DISPLAY INVISIBLE (-7900 1800);
FORCEPROP 1 LAST HDL_TAP TRUE
J 2
(-8225 1625);
DISPLAY 0.872340 (-8225 1625);
DISPLAY INVISIBLE (-8225 1625);
FORCEPROP 1 LAST PATH I82
J 2
(-7898 1750);
DISPLAY 0.872340 (-7898 1750);
PAINT GREEN (-7898 1750);
DISPLAY INVISIBLE (-7898 1750);
FORCEADD TAP..1
R 2
(-7650 1600);
FORCEPROP 3 LASTPIN (-7600 1600) SIG_NAME P5E_CPU0_P1_TX_BUF_DP<11>
J 0
(-7590 1610);
DISPLAY 0.659574 (-7590 1610);
PAINT MONO (-7590 1610);
DISPLAY INVISIBLE (-7590 1610);
FORCEPROP 1 LASTPIN (-7600 1600) BN 11
J 2
(-7588 1608);
DISPLAY 0.680851 (-7588 1608);
PAINT GREEN (-7588 1608);
FORCEPROP 2 LAST CDS_LIB standard
J 0
(-7650 1600);
DISPLAY INVISIBLE (-7650 1600);
FORCEPROP 1 LAST BODY_TYPE PLUMBING
J 2
(-7650 1650);
DISPLAY 0.872340 (-7650 1650);
PAINT GREEN (-7650 1650);
DISPLAY INVISIBLE (-7650 1650);
FORCEPROP 1 LAST HDL_TAP TRUE
J 2
(-7975 1475);
DISPLAY 0.872340 (-7975 1475);
DISPLAY INVISIBLE (-7975 1475);
FORCEPROP 1 LAST PATH I83
J 2
(-7648 1600);
DISPLAY 0.872340 (-7648 1600);
PAINT GREEN (-7648 1600);
DISPLAY INVISIBLE (-7648 1600);
FORCEADD TAP..1
R 2
(-7650 1400);
FORCEPROP 3 LASTPIN (-7600 1400) SIG_NAME P5E_CPU0_P1_TX_BUF_DP<12>
J 0
(-7590 1410);
DISPLAY 0.659574 (-7590 1410);
PAINT MONO (-7590 1410);
DISPLAY INVISIBLE (-7590 1410);
FORCEPROP 1 LASTPIN (-7600 1400) BN 12
J 2
(-7588 1408);
DISPLAY 0.680851 (-7588 1408);
PAINT GREEN (-7588 1408);
FORCEPROP 2 LAST CDS_LIB standard
J 0
(-7650 1400);
DISPLAY INVISIBLE (-7650 1400);
FORCEPROP 1 LAST BODY_TYPE PLUMBING
J 2
(-7650 1450);
DISPLAY 0.872340 (-7650 1450);
PAINT GREEN (-7650 1450);
DISPLAY INVISIBLE (-7650 1450);
FORCEPROP 1 LAST HDL_TAP TRUE
J 2
(-7975 1275);
DISPLAY 0.872340 (-7975 1275);
DISPLAY INVISIBLE (-7975 1275);
FORCEPROP 1 LAST PATH I84
J 2
(-7648 1400);
DISPLAY 0.872340 (-7648 1400);
PAINT GREEN (-7648 1400);
DISPLAY INVISIBLE (-7648 1400);
FORCEADD TAP..1
R 2
(-7650 1800);
FORCEPROP 3 LASTPIN (-7600 1800) SIG_NAME P5E_CPU0_P1_TX_BUF_DP<10>
J 0
(-7590 1810);
DISPLAY 0.659574 (-7590 1810);
PAINT MONO (-7590 1810);
DISPLAY INVISIBLE (-7590 1810);
FORCEPROP 1 LASTPIN (-7600 1800) BN 10
J 2
(-7588 1808);
DISPLAY 0.680851 (-7588 1808);
PAINT GREEN (-7588 1808);
FORCEPROP 2 LAST CDS_LIB standard
J 0
(-7650 1800);
DISPLAY INVISIBLE (-7650 1800);
FORCEPROP 1 LAST BODY_TYPE PLUMBING
J 2
(-7650 1850);
DISPLAY 0.872340 (-7650 1850);
PAINT GREEN (-7650 1850);
DISPLAY INVISIBLE (-7650 1850);
FORCEPROP 1 LAST HDL_TAP TRUE
J 2
(-7975 1675);
DISPLAY 0.872340 (-7975 1675);
DISPLAY INVISIBLE (-7975 1675);
FORCEPROP 1 LAST PATH I85
J 2
(-7648 1800);
DISPLAY 0.872340 (-7648 1800);
PAINT GREEN (-7648 1800);
DISPLAY INVISIBLE (-7648 1800);
FORCEADD Q_CAP_DIFFBUS..2
R 2
(-6925 750);
FORCEPROP 1 LAST LOCATION C6564
J 2
(-6650 750);
DISPLAY 0.723404 (-6650 750);
PAINT GREEN (-6650 750);
FORCEPROP 2 LAST $SEC 1
J 2
(-6750 825);
DISPLAY 0.680851 (-6750 825);
PAINT MONO (-6750 825);
DISPLAY INVISIBLE (-6750 825);
FORCEPROP 2 LAST CDS_SEC 1
J 2
(-6750 825);
DISPLAY 0.680851 (-6750 825);
DISPLAY INVISIBLE (-6750 825);
FORCEPROP 2 LASTPIN (-6850 750) $PN 1
J 0
(-6840 760);
DISPLAY 0.808511 (-6840 760);
FORCEPROP 2 LASTPIN (-7000 750) $PN 2
J 2
(-7010 760);
DISPLAY 0.808511 (-7010 760);
FORCEPROP 2 LAST VALUE DIFF BUS_0.22UF
J 2
(-7075 750);
DISPLAY 0.553191 (-7075 750);
FORCEPROP 2 LAST TOLERANCE 20%
J 2
(-7000 800);
DISPLAY 0.553191 (-7000 800);
DISPLAY INVISIBLE (-7000 800);
FORCEPROP 2 LAST PACK_TYPE C0201
J 2
(-7100 800);
DISPLAY 0.553191 (-7100 800);
DISPLAY INVISIBLE (-7100 800);
FORCEPROP 1 LAST MATERIAL X6S
J 2
(-6916 829);
DISPLAY 0.574468 (-6916 829);
PAINT GREEN (-6916 829);
DISPLAY INVISIBLE (-6916 829);
FORCEPROP 2 LAST VOLTAGE 6.3V
J 2
(-7275 800);
DISPLAY 0.553191 (-7275 800);
DISPLAY INVISIBLE (-7275 800);
FORCEPROP 1 LAST PIN_NAMES_ROTATE TRUE
J 2
(-6925 750);
DISPLAY 0.489362 (-6925 750);
PAINT GREEN (-6925 750);
DISPLAY INVISIBLE (-6925 750);
FORCEPROP 2 LAST CDS_LIB pure_quanta
J 2
(-6925 750);
DISPLAY INVISIBLE (-6925 750);
FORCEPROP 1 LAST CDS_LMAN_SYM_OUTLINE -25,50,25,-50
J 2
(-6925 750);
DISPLAY 0.468085 (-6925 750);
PAINT GREEN (-6925 750);
DISPLAY INVISIBLE (-6925 750);
FORCEPROP 1 LAST PATH I86
J 2
(-6925 750);
DISPLAY 0.723404 (-6925 750);
DISPLAY INVISIBLE (-6925 750);
FORCEPROP 1 LAST PART_NUMBER SP_CH4221MEE01
J 2
(-7041 838);
DISPLAY 0.574468 (-7041 838);
PAINT GREEN (-7041 838);
DISPLAY INVISIBLE (-7041 838);
FORCEPROP 1 LAST LOCATION C6564
J 0
(-6675 825);
DISPLAY 1.021277 (-6675 825);
DISPLAY INVISIBLE (-6675 825);
FORCEADD Q_CAP_DIFFBUS..2
R 2
(-6925 800);
FORCEPROP 1 LAST LOCATION C6563
J 2
(-6650 800);
DISPLAY 0.723404 (-6650 800);
PAINT GREEN (-6650 800);
FORCEPROP 2 LAST $SEC 1
J 2
(-6750 875);
DISPLAY 0.680851 (-6750 875);
PAINT MONO (-6750 875);
DISPLAY INVISIBLE (-6750 875);
FORCEPROP 2 LAST CDS_SEC 1
J 2
(-6750 875);
DISPLAY 0.680851 (-6750 875);
DISPLAY INVISIBLE (-6750 875);
FORCEPROP 2 LASTPIN (-6850 800) $PN 1
J 0
(-6840 810);
DISPLAY 0.808511 (-6840 810);
FORCEPROP 2 LASTPIN (-7000 800) $PN 2
J 2
(-7010 810);
DISPLAY 0.808511 (-7010 810);
FORCEPROP 2 LAST VALUE DIFF BUS_0.22UF
J 2
(-7075 800);
DISPLAY 0.553191 (-7075 800);
FORCEPROP 2 LAST TOLERANCE 20%
J 2
(-7000 850);
DISPLAY 0.553191 (-7000 850);
DISPLAY INVISIBLE (-7000 850);
FORCEPROP 2 LAST PACK_TYPE C0201
J 2
(-7100 850);
DISPLAY 0.553191 (-7100 850);
DISPLAY INVISIBLE (-7100 850);
FORCEPROP 1 LAST MATERIAL X6S
J 2
(-6916 879);
DISPLAY 0.574468 (-6916 879);
PAINT GREEN (-6916 879);
DISPLAY INVISIBLE (-6916 879);
FORCEPROP 2 LAST VOLTAGE 6.3V
J 2
(-7275 850);
DISPLAY 0.553191 (-7275 850);
DISPLAY INVISIBLE (-7275 850);
FORCEPROP 1 LAST PIN_NAMES_ROTATE TRUE
J 2
(-6925 800);
DISPLAY 0.489362 (-6925 800);
PAINT GREEN (-6925 800);
DISPLAY INVISIBLE (-6925 800);
FORCEPROP 2 LAST CDS_LIB pure_quanta
J 2
(-6925 800);
DISPLAY INVISIBLE (-6925 800);
FORCEPROP 1 LAST CDS_LMAN_SYM_OUTLINE -25,50,25,-50
J 2
(-6925 800);
DISPLAY 0.468085 (-6925 800);
PAINT GREEN (-6925 800);
DISPLAY INVISIBLE (-6925 800);
FORCEPROP 1 LAST PATH I87
J 2
(-6925 800);
DISPLAY 0.723404 (-6925 800);
DISPLAY INVISIBLE (-6925 800);
FORCEPROP 1 LAST PART_NUMBER SP_CH4221MEE01
J 2
(-7041 888);
DISPLAY 0.574468 (-7041 888);
PAINT GREEN (-7041 888);
DISPLAY INVISIBLE (-7041 888);
FORCEPROP 1 LAST LOCATION C6563
J 0
(-6675 875);
DISPLAY 1.021277 (-6675 875);
DISPLAY INVISIBLE (-6675 875);
FORCEADD Q_CAP_DIFFBUS..2
R 2
(-6925 950);
FORCEPROP 1 LAST LOCATION C6562
J 2
(-6650 950);
DISPLAY 0.723404 (-6650 950);
PAINT GREEN (-6650 950);
FORCEPROP 2 LAST $SEC 1
J 2
(-6750 1025);
DISPLAY 0.680851 (-6750 1025);
PAINT MONO (-6750 1025);
DISPLAY INVISIBLE (-6750 1025);
FORCEPROP 2 LAST CDS_SEC 1
J 2
(-6750 1025);
DISPLAY 0.680851 (-6750 1025);
DISPLAY INVISIBLE (-6750 1025);
FORCEPROP 2 LASTPIN (-6850 950) $PN 1
J 0
(-6840 960);
DISPLAY 0.808511 (-6840 960);
FORCEPROP 2 LASTPIN (-7000 950) $PN 2
J 2
(-7010 960);
DISPLAY 0.808511 (-7010 960);
FORCEPROP 2 LAST VALUE DIFF BUS_0.22UF
J 2
(-7075 950);
DISPLAY 0.553191 (-7075 950);
FORCEPROP 2 LAST TOLERANCE 20%
J 2
(-7000 1000);
DISPLAY 0.553191 (-7000 1000);
DISPLAY INVISIBLE (-7000 1000);
FORCEPROP 2 LAST PACK_TYPE C0201
J 2
(-7100 1000);
DISPLAY 0.553191 (-7100 1000);
DISPLAY INVISIBLE (-7100 1000);
FORCEPROP 1 LAST MATERIAL X6S
J 2
(-6916 1029);
DISPLAY 0.574468 (-6916 1029);
PAINT GREEN (-6916 1029);
DISPLAY INVISIBLE (-6916 1029);
FORCEPROP 2 LAST VOLTAGE 6.3V
J 2
(-7275 1000);
DISPLAY 0.553191 (-7275 1000);
DISPLAY INVISIBLE (-7275 1000);
FORCEPROP 1 LAST PIN_NAMES_ROTATE TRUE
J 2
(-6925 950);
DISPLAY 0.489362 (-6925 950);
PAINT GREEN (-6925 950);
DISPLAY INVISIBLE (-6925 950);
FORCEPROP 2 LAST CDS_LIB pure_quanta
J 2
(-6925 950);
DISPLAY INVISIBLE (-6925 950);
FORCEPROP 1 LAST CDS_LMAN_SYM_OUTLINE -25,50,25,-50
J 2
(-6925 950);
DISPLAY 0.468085 (-6925 950);
PAINT GREEN (-6925 950);
DISPLAY INVISIBLE (-6925 950);
FORCEPROP 1 LAST PATH I88
J 2
(-6925 950);
DISPLAY 0.723404 (-6925 950);
DISPLAY INVISIBLE (-6925 950);
FORCEPROP 1 LAST PART_NUMBER SP_CH4221MEE01
J 2
(-7041 1038);
DISPLAY 0.574468 (-7041 1038);
PAINT GREEN (-7041 1038);
DISPLAY INVISIBLE (-7041 1038);
FORCEPROP 1 LAST LOCATION C6562
J 0
(-6675 1025);
DISPLAY 1.021277 (-6675 1025);
DISPLAY INVISIBLE (-6675 1025);
FORCEADD Q_CAP_DIFFBUS..2
R 2
(-6925 1000);
FORCEPROP 1 LAST LOCATION C6561
J 2
(-6650 1000);
DISPLAY 0.723404 (-6650 1000);
PAINT GREEN (-6650 1000);
FORCEPROP 2 LAST $SEC 1
J 2
(-6750 1075);
DISPLAY 0.680851 (-6750 1075);
PAINT MONO (-6750 1075);
DISPLAY INVISIBLE (-6750 1075);
FORCEPROP 2 LAST CDS_SEC 1
J 2
(-6750 1075);
DISPLAY 0.680851 (-6750 1075);
DISPLAY INVISIBLE (-6750 1075);
FORCEPROP 2 LASTPIN (-6850 1000) $PN 1
J 0
(-6840 1010);
DISPLAY 0.808511 (-6840 1010);
FORCEPROP 2 LASTPIN (-7000 1000) $PN 2
J 2
(-7010 1010);
DISPLAY 0.808511 (-7010 1010);
FORCEPROP 2 LAST VALUE DIFF BUS_0.22UF
J 2
(-7075 1000);
DISPLAY 0.553191 (-7075 1000);
FORCEPROP 2 LAST TOLERANCE 20%
J 2
(-7000 1050);
DISPLAY 0.553191 (-7000 1050);
DISPLAY INVISIBLE (-7000 1050);
FORCEPROP 2 LAST PACK_TYPE C0201
J 2
(-7100 1050);
DISPLAY 0.553191 (-7100 1050);
DISPLAY INVISIBLE (-7100 1050);
FORCEPROP 1 LAST MATERIAL X6S
J 2
(-6916 1079);
DISPLAY 0.574468 (-6916 1079);
PAINT GREEN (-6916 1079);
DISPLAY INVISIBLE (-6916 1079);
FORCEPROP 2 LAST VOLTAGE 6.3V
J 2
(-7275 1050);
DISPLAY 0.553191 (-7275 1050);
DISPLAY INVISIBLE (-7275 1050);
FORCEPROP 1 LAST PIN_NAMES_ROTATE TRUE
J 2
(-6925 1000);
DISPLAY 0.489362 (-6925 1000);
PAINT GREEN (-6925 1000);
DISPLAY INVISIBLE (-6925 1000);
FORCEPROP 1 LAST CDS_LMAN_SYM_OUTLINE -25,50,25,-50
J 2
(-6925 1000);
DISPLAY 0.468085 (-6925 1000);
PAINT GREEN (-6925 1000);
DISPLAY INVISIBLE (-6925 1000);
FORCEPROP 2 LAST CDS_LIB pure_quanta
J 2
(-6925 1000);
DISPLAY INVISIBLE (-6925 1000);
FORCEPROP 1 LAST PATH I89
J 2
(-6925 1000);
DISPLAY 0.723404 (-6925 1000);
DISPLAY INVISIBLE (-6925 1000);
FORCEPROP 1 LAST PART_NUMBER SP_CH4221MEE01
J 2
(-7041 1088);
DISPLAY 0.574468 (-7041 1088);
PAINT GREEN (-7041 1088);
DISPLAY INVISIBLE (-7041 1088);
FORCEPROP 1 LAST LOCATION C6561
J 0
(-6675 1075);
DISPLAY 1.021277 (-6675 1075);
DISPLAY INVISIBLE (-6675 1075);
FORCEADD TAP..1
R 2
(-3125 800);
FORCEPROP 3 LASTPIN (-3075 800) SIG_NAME P5E_CPU0_P1_TX_BUF_DP<7>
J 0
(-3065 810);
DISPLAY 0.659574 (-3065 810);
PAINT MONO (-3065 810);
DISPLAY INVISIBLE (-3065 810);
FORCEPROP 1 LASTPIN (-3075 800) BN 7
J 2
(-3063 808);
DISPLAY 0.680851 (-3063 808);
PAINT GREEN (-3063 808);
FORCEPROP 2 LAST CDS_LIB standard
J 0
(-3125 800);
DISPLAY INVISIBLE (-3125 800);
FORCEPROP 1 LAST BODY_TYPE PLUMBING
J 2
(-3125 850);
DISPLAY 0.872340 (-3125 850);
PAINT GREEN (-3125 850);
DISPLAY INVISIBLE (-3125 850);
FORCEPROP 1 LAST HDL_TAP TRUE
J 2
(-3450 675);
DISPLAY 0.872340 (-3450 675);
DISPLAY INVISIBLE (-3450 675);
FORCEPROP 1 LAST PATH I9
J 2
(-3123 800);
DISPLAY 0.872340 (-3123 800);
PAINT GREEN (-3123 800);
DISPLAY INVISIBLE (-3123 800);
FORCEADD Q_CAP_DIFFBUS..2
R 2
(-6925 1150);
FORCEPROP 1 LAST LOCATION C6560
J 2
(-6650 1150);
DISPLAY 0.723404 (-6650 1150);
PAINT GREEN (-6650 1150);
FORCEPROP 2 LAST $SEC 1
J 2
(-6750 1225);
DISPLAY 0.680851 (-6750 1225);
PAINT MONO (-6750 1225);
DISPLAY INVISIBLE (-6750 1225);
FORCEPROP 2 LAST CDS_SEC 1
J 2
(-6750 1225);
DISPLAY 0.680851 (-6750 1225);
DISPLAY INVISIBLE (-6750 1225);
FORCEPROP 2 LASTPIN (-6850 1150) $PN 1
J 0
(-6840 1160);
DISPLAY 0.808511 (-6840 1160);
FORCEPROP 2 LASTPIN (-7000 1150) $PN 2
J 2
(-7010 1160);
DISPLAY 0.808511 (-7010 1160);
FORCEPROP 2 LAST VALUE DIFF BUS_0.22UF
J 2
(-7075 1150);
DISPLAY 0.553191 (-7075 1150);
FORCEPROP 2 LAST TOLERANCE 20%
J 2
(-7000 1200);
DISPLAY 0.553191 (-7000 1200);
DISPLAY INVISIBLE (-7000 1200);
FORCEPROP 2 LAST PACK_TYPE C0201
J 2
(-7100 1200);
DISPLAY 0.553191 (-7100 1200);
DISPLAY INVISIBLE (-7100 1200);
FORCEPROP 1 LAST MATERIAL X6S
J 2
(-6916 1229);
DISPLAY 0.574468 (-6916 1229);
PAINT GREEN (-6916 1229);
DISPLAY INVISIBLE (-6916 1229);
FORCEPROP 2 LAST VOLTAGE 6.3V
J 2
(-7275 1200);
DISPLAY 0.553191 (-7275 1200);
DISPLAY INVISIBLE (-7275 1200);
FORCEPROP 1 LAST PIN_NAMES_ROTATE TRUE
J 2
(-6925 1150);
DISPLAY 0.489362 (-6925 1150);
PAINT GREEN (-6925 1150);
DISPLAY INVISIBLE (-6925 1150);
FORCEPROP 2 LAST CDS_LIB pure_quanta
J 2
(-6925 1150);
DISPLAY INVISIBLE (-6925 1150);
FORCEPROP 1 LAST CDS_LMAN_SYM_OUTLINE -25,50,25,-50
J 2
(-6925 1150);
DISPLAY 0.468085 (-6925 1150);
PAINT GREEN (-6925 1150);
DISPLAY INVISIBLE (-6925 1150);
FORCEPROP 1 LAST PATH I90
J 2
(-6925 1150);
DISPLAY 0.723404 (-6925 1150);
DISPLAY INVISIBLE (-6925 1150);
FORCEPROP 1 LAST PART_NUMBER SP_CH4221MEE01
J 2
(-7041 1238);
DISPLAY 0.574468 (-7041 1238);
PAINT GREEN (-7041 1238);
DISPLAY INVISIBLE (-7041 1238);
FORCEPROP 1 LAST LOCATION C6560
J 0
(-6675 1225);
DISPLAY 1.021277 (-6675 1225);
DISPLAY INVISIBLE (-6675 1225);
FORCEADD Q_CAP_DIFFBUS..2
R 2
(-6925 1200);
FORCEPROP 1 LAST LOCATION C6559
J 2
(-6650 1200);
DISPLAY 0.723404 (-6650 1200);
PAINT GREEN (-6650 1200);
FORCEPROP 2 LAST $SEC 1
J 2
(-6750 1275);
DISPLAY 0.680851 (-6750 1275);
PAINT MONO (-6750 1275);
DISPLAY INVISIBLE (-6750 1275);
FORCEPROP 2 LAST CDS_SEC 1
J 2
(-6750 1275);
DISPLAY 0.680851 (-6750 1275);
DISPLAY INVISIBLE (-6750 1275);
FORCEPROP 2 LASTPIN (-6850 1200) $PN 1
J 0
(-6840 1210);
DISPLAY 0.808511 (-6840 1210);
FORCEPROP 2 LASTPIN (-7000 1200) $PN 2
J 2
(-7010 1210);
DISPLAY 0.808511 (-7010 1210);
FORCEPROP 2 LAST VALUE DIFF BUS_0.22UF
J 2
(-7075 1200);
DISPLAY 0.553191 (-7075 1200);
FORCEPROP 2 LAST TOLERANCE 20%
J 2
(-7000 1250);
DISPLAY 0.553191 (-7000 1250);
DISPLAY INVISIBLE (-7000 1250);
FORCEPROP 2 LAST PACK_TYPE C0201
J 2
(-7100 1250);
DISPLAY 0.553191 (-7100 1250);
DISPLAY INVISIBLE (-7100 1250);
FORCEPROP 1 LAST MATERIAL X6S
J 2
(-6916 1279);
DISPLAY 0.574468 (-6916 1279);
PAINT GREEN (-6916 1279);
DISPLAY INVISIBLE (-6916 1279);
FORCEPROP 2 LAST VOLTAGE 6.3V
J 2
(-7275 1250);
DISPLAY 0.553191 (-7275 1250);
DISPLAY INVISIBLE (-7275 1250);
FORCEPROP 1 LAST PIN_NAMES_ROTATE TRUE
J 2
(-6925 1200);
DISPLAY 0.489362 (-6925 1200);
PAINT GREEN (-6925 1200);
DISPLAY INVISIBLE (-6925 1200);
FORCEPROP 2 LAST CDS_LIB pure_quanta
J 2
(-6925 1200);
DISPLAY INVISIBLE (-6925 1200);
FORCEPROP 1 LAST CDS_LMAN_SYM_OUTLINE -25,50,25,-50
J 2
(-6925 1200);
DISPLAY 0.468085 (-6925 1200);
PAINT GREEN (-6925 1200);
DISPLAY INVISIBLE (-6925 1200);
FORCEPROP 1 LAST PATH I91
J 2
(-6925 1200);
DISPLAY 0.723404 (-6925 1200);
DISPLAY INVISIBLE (-6925 1200);
FORCEPROP 1 LAST PART_NUMBER SP_CH4221MEE01
J 2
(-7041 1288);
DISPLAY 0.574468 (-7041 1288);
PAINT GREEN (-7041 1288);
DISPLAY INVISIBLE (-7041 1288);
FORCEPROP 1 LAST LOCATION C6559
J 0
(-6675 1275);
DISPLAY 1.021277 (-6675 1275);
DISPLAY INVISIBLE (-6675 1275);
FORCEADD Q_CAP_DIFFBUS..2
R 2
(-6925 1350);
FORCEPROP 1 LAST LOCATION C6558
J 2
(-6650 1350);
DISPLAY 0.723404 (-6650 1350);
PAINT GREEN (-6650 1350);
FORCEPROP 2 LAST $SEC 1
J 2
(-6750 1425);
DISPLAY 0.680851 (-6750 1425);
PAINT MONO (-6750 1425);
DISPLAY INVISIBLE (-6750 1425);
FORCEPROP 2 LAST CDS_SEC 1
J 2
(-6750 1425);
DISPLAY 0.680851 (-6750 1425);
DISPLAY INVISIBLE (-6750 1425);
FORCEPROP 2 LASTPIN (-6850 1350) $PN 1
J 0
(-6840 1360);
DISPLAY 0.808511 (-6840 1360);
FORCEPROP 2 LASTPIN (-7000 1350) $PN 2
J 2
(-7010 1360);
DISPLAY 0.808511 (-7010 1360);
FORCEPROP 2 LAST VALUE DIFF BUS_0.22UF
J 2
(-7075 1350);
DISPLAY 0.553191 (-7075 1350);
FORCEPROP 2 LAST TOLERANCE 20%
J 2
(-7000 1400);
DISPLAY 0.553191 (-7000 1400);
DISPLAY INVISIBLE (-7000 1400);
FORCEPROP 2 LAST PACK_TYPE C0201
J 2
(-7100 1400);
DISPLAY 0.553191 (-7100 1400);
DISPLAY INVISIBLE (-7100 1400);
FORCEPROP 1 LAST MATERIAL X6S
J 2
(-6916 1429);
DISPLAY 0.574468 (-6916 1429);
PAINT GREEN (-6916 1429);
DISPLAY INVISIBLE (-6916 1429);
FORCEPROP 2 LAST VOLTAGE 6.3V
J 2
(-7275 1400);
DISPLAY 0.553191 (-7275 1400);
DISPLAY INVISIBLE (-7275 1400);
FORCEPROP 1 LAST PIN_NAMES_ROTATE TRUE
J 2
(-6925 1350);
DISPLAY 0.489362 (-6925 1350);
PAINT GREEN (-6925 1350);
DISPLAY INVISIBLE (-6925 1350);
FORCEPROP 1 LAST CDS_LMAN_SYM_OUTLINE -25,50,25,-50
J 2
(-6925 1350);
DISPLAY 0.468085 (-6925 1350);
PAINT GREEN (-6925 1350);
DISPLAY INVISIBLE (-6925 1350);
FORCEPROP 2 LAST CDS_LIB pure_quanta
J 2
(-6925 1350);
DISPLAY INVISIBLE (-6925 1350);
FORCEPROP 1 LAST PATH I92
J 2
(-6925 1350);
DISPLAY 0.723404 (-6925 1350);
DISPLAY INVISIBLE (-6925 1350);
FORCEPROP 1 LAST PART_NUMBER SP_CH4221MEE01
J 2
(-7041 1438);
DISPLAY 0.574468 (-7041 1438);
PAINT GREEN (-7041 1438);
DISPLAY INVISIBLE (-7041 1438);
FORCEPROP 1 LAST LOCATION C6558
J 0
(-6675 1425);
DISPLAY 1.021277 (-6675 1425);
DISPLAY INVISIBLE (-6675 1425);
FORCEADD Q_CAP_DIFFBUS..2
R 2
(-6925 1400);
FORCEPROP 1 LAST LOCATION C6557
J 2
(-6650 1400);
DISPLAY 0.723404 (-6650 1400);
PAINT GREEN (-6650 1400);
FORCEPROP 2 LAST $SEC 1
J 2
(-6750 1475);
DISPLAY 0.680851 (-6750 1475);
PAINT MONO (-6750 1475);
DISPLAY INVISIBLE (-6750 1475);
FORCEPROP 2 LAST CDS_SEC 1
J 2
(-6750 1475);
DISPLAY 0.680851 (-6750 1475);
DISPLAY INVISIBLE (-6750 1475);
FORCEPROP 2 LASTPIN (-6850 1400) $PN 1
J 0
(-6840 1410);
DISPLAY 0.808511 (-6840 1410);
FORCEPROP 2 LASTPIN (-7000 1400) $PN 2
J 2
(-7010 1410);
DISPLAY 0.808511 (-7010 1410);
FORCEPROP 2 LAST VALUE DIFF BUS_0.22UF
J 2
(-7075 1400);
DISPLAY 0.553191 (-7075 1400);
FORCEPROP 2 LAST TOLERANCE 20%
J 2
(-7000 1450);
DISPLAY 0.553191 (-7000 1450);
DISPLAY INVISIBLE (-7000 1450);
FORCEPROP 2 LAST PACK_TYPE C0201
J 2
(-7100 1450);
DISPLAY 0.553191 (-7100 1450);
DISPLAY INVISIBLE (-7100 1450);
FORCEPROP 1 LAST MATERIAL X6S
J 2
(-6916 1479);
DISPLAY 0.574468 (-6916 1479);
PAINT GREEN (-6916 1479);
DISPLAY INVISIBLE (-6916 1479);
FORCEPROP 2 LAST VOLTAGE 6.3V
J 2
(-7275 1450);
DISPLAY 0.553191 (-7275 1450);
DISPLAY INVISIBLE (-7275 1450);
FORCEPROP 1 LAST PIN_NAMES_ROTATE TRUE
J 2
(-6925 1400);
DISPLAY 0.489362 (-6925 1400);
PAINT GREEN (-6925 1400);
DISPLAY INVISIBLE (-6925 1400);
FORCEPROP 1 LAST CDS_LMAN_SYM_OUTLINE -25,50,25,-50
J 2
(-6925 1400);
DISPLAY 0.468085 (-6925 1400);
PAINT GREEN (-6925 1400);
DISPLAY INVISIBLE (-6925 1400);
FORCEPROP 2 LAST CDS_LIB pure_quanta
J 2
(-6925 1400);
DISPLAY INVISIBLE (-6925 1400);
FORCEPROP 1 LAST PATH I93
J 2
(-6925 1400);
DISPLAY 0.723404 (-6925 1400);
DISPLAY INVISIBLE (-6925 1400);
FORCEPROP 1 LAST PART_NUMBER SP_CH4221MEE01
J 2
(-7041 1488);
DISPLAY 0.574468 (-7041 1488);
PAINT GREEN (-7041 1488);
DISPLAY INVISIBLE (-7041 1488);
FORCEPROP 1 LAST LOCATION C6557
J 0
(-6675 1475);
DISPLAY 1.021277 (-6675 1475);
DISPLAY INVISIBLE (-6675 1475);
FORCEADD Q_CAP_DIFFBUS..2
R 2
(-6925 1550);
FORCEPROP 1 LAST LOCATION C6556
J 2
(-6650 1550);
DISPLAY 0.723404 (-6650 1550);
PAINT GREEN (-6650 1550);
FORCEPROP 2 LAST $SEC 1
J 2
(-6750 1625);
DISPLAY 0.680851 (-6750 1625);
PAINT MONO (-6750 1625);
DISPLAY INVISIBLE (-6750 1625);
FORCEPROP 2 LAST CDS_SEC 1
J 2
(-6750 1625);
DISPLAY 0.680851 (-6750 1625);
DISPLAY INVISIBLE (-6750 1625);
FORCEPROP 2 LASTPIN (-6850 1550) $PN 1
J 0
(-6840 1560);
DISPLAY 0.808511 (-6840 1560);
FORCEPROP 2 LASTPIN (-7000 1550) $PN 2
J 2
(-7010 1560);
DISPLAY 0.808511 (-7010 1560);
FORCEPROP 2 LAST VALUE DIFF BUS_0.22UF
J 2
(-7075 1550);
DISPLAY 0.553191 (-7075 1550);
FORCEPROP 2 LAST TOLERANCE 20%
J 2
(-7000 1600);
DISPLAY 0.553191 (-7000 1600);
DISPLAY INVISIBLE (-7000 1600);
FORCEPROP 2 LAST PACK_TYPE C0201
J 2
(-7100 1600);
DISPLAY 0.553191 (-7100 1600);
DISPLAY INVISIBLE (-7100 1600);
FORCEPROP 1 LAST MATERIAL X6S
J 2
(-6916 1629);
DISPLAY 0.574468 (-6916 1629);
PAINT GREEN (-6916 1629);
DISPLAY INVISIBLE (-6916 1629);
FORCEPROP 2 LAST VOLTAGE 6.3V
J 2
(-7275 1600);
DISPLAY 0.553191 (-7275 1600);
DISPLAY INVISIBLE (-7275 1600);
FORCEPROP 1 LAST PIN_NAMES_ROTATE TRUE
J 2
(-6925 1550);
DISPLAY 0.489362 (-6925 1550);
PAINT GREEN (-6925 1550);
DISPLAY INVISIBLE (-6925 1550);
FORCEPROP 2 LAST CDS_LIB pure_quanta
J 2
(-6925 1550);
DISPLAY INVISIBLE (-6925 1550);
FORCEPROP 1 LAST CDS_LMAN_SYM_OUTLINE -25,50,25,-50
J 2
(-6925 1550);
DISPLAY 0.468085 (-6925 1550);
PAINT GREEN (-6925 1550);
DISPLAY INVISIBLE (-6925 1550);
FORCEPROP 1 LAST PATH I94
J 2
(-6925 1550);
DISPLAY 0.723404 (-6925 1550);
DISPLAY INVISIBLE (-6925 1550);
FORCEPROP 1 LAST PART_NUMBER SP_CH4221MEE01
J 2
(-7041 1638);
DISPLAY 0.574468 (-7041 1638);
PAINT GREEN (-7041 1638);
DISPLAY INVISIBLE (-7041 1638);
FORCEPROP 1 LAST LOCATION C6556
J 0
(-6675 1625);
DISPLAY 1.021277 (-6675 1625);
DISPLAY INVISIBLE (-6675 1625);
FORCEADD Q_CAP_DIFFBUS..2
R 2
(-6925 1600);
FORCEPROP 1 LAST LOCATION C6555
J 2
(-6650 1600);
DISPLAY 0.723404 (-6650 1600);
PAINT GREEN (-6650 1600);
FORCEPROP 2 LAST $SEC 1
J 2
(-6750 1675);
DISPLAY 0.680851 (-6750 1675);
PAINT MONO (-6750 1675);
DISPLAY INVISIBLE (-6750 1675);
FORCEPROP 2 LAST CDS_SEC 1
J 2
(-6750 1675);
DISPLAY 0.680851 (-6750 1675);
DISPLAY INVISIBLE (-6750 1675);
FORCEPROP 2 LASTPIN (-6850 1600) $PN 1
J 0
(-6840 1610);
DISPLAY 0.808511 (-6840 1610);
FORCEPROP 2 LASTPIN (-7000 1600) $PN 2
J 2
(-7010 1610);
DISPLAY 0.808511 (-7010 1610);
FORCEPROP 2 LAST VALUE DIFF BUS_0.22UF
J 2
(-7075 1600);
DISPLAY 0.553191 (-7075 1600);
FORCEPROP 2 LAST TOLERANCE 20%
J 2
(-7000 1650);
DISPLAY 0.553191 (-7000 1650);
DISPLAY INVISIBLE (-7000 1650);
FORCEPROP 2 LAST PACK_TYPE C0201
J 2
(-7100 1650);
DISPLAY 0.553191 (-7100 1650);
DISPLAY INVISIBLE (-7100 1650);
FORCEPROP 1 LAST MATERIAL X6S
J 2
(-6916 1679);
DISPLAY 0.574468 (-6916 1679);
PAINT GREEN (-6916 1679);
DISPLAY INVISIBLE (-6916 1679);
FORCEPROP 2 LAST VOLTAGE 6.3V
J 2
(-7275 1650);
DISPLAY 0.553191 (-7275 1650);
DISPLAY INVISIBLE (-7275 1650);
FORCEPROP 1 LAST PIN_NAMES_ROTATE TRUE
J 2
(-6925 1600);
DISPLAY 0.489362 (-6925 1600);
PAINT GREEN (-6925 1600);
DISPLAY INVISIBLE (-6925 1600);
FORCEPROP 2 LAST CDS_LIB pure_quanta
J 2
(-6925 1600);
DISPLAY INVISIBLE (-6925 1600);
FORCEPROP 1 LAST CDS_LMAN_SYM_OUTLINE -25,50,25,-50
J 2
(-6925 1600);
DISPLAY 0.468085 (-6925 1600);
PAINT GREEN (-6925 1600);
DISPLAY INVISIBLE (-6925 1600);
FORCEPROP 1 LAST PATH I95
J 2
(-6925 1600);
DISPLAY 0.723404 (-6925 1600);
DISPLAY INVISIBLE (-6925 1600);
FORCEPROP 1 LAST PART_NUMBER SP_CH4221MEE01
J 2
(-7041 1688);
DISPLAY 0.574468 (-7041 1688);
PAINT GREEN (-7041 1688);
DISPLAY INVISIBLE (-7041 1688);
FORCEPROP 1 LAST LOCATION C6555
J 0
(-6675 1675);
DISPLAY 1.021277 (-6675 1675);
DISPLAY INVISIBLE (-6675 1675);
FORCEADD Q_CAP_DIFFBUS..2
R 2
(-6925 1800);
FORCEPROP 1 LAST LOCATION C6553
J 2
(-6650 1800);
DISPLAY 0.723404 (-6650 1800);
PAINT GREEN (-6650 1800);
FORCEPROP 2 LAST $SEC 1
J 2
(-6750 1875);
DISPLAY 0.680851 (-6750 1875);
PAINT MONO (-6750 1875);
DISPLAY INVISIBLE (-6750 1875);
FORCEPROP 2 LAST CDS_SEC 1
J 2
(-6750 1875);
DISPLAY 0.680851 (-6750 1875);
DISPLAY INVISIBLE (-6750 1875);
FORCEPROP 2 LASTPIN (-6850 1800) $PN 1
J 0
(-6840 1810);
DISPLAY 0.808511 (-6840 1810);
FORCEPROP 2 LASTPIN (-7000 1800) $PN 2
J 2
(-7010 1810);
DISPLAY 0.808511 (-7010 1810);
FORCEPROP 2 LAST VALUE DIFF BUS_0.22UF
J 2
(-7075 1800);
DISPLAY 0.553191 (-7075 1800);
FORCEPROP 2 LAST TOLERANCE 20%
J 2
(-7000 1850);
DISPLAY 0.553191 (-7000 1850);
DISPLAY INVISIBLE (-7000 1850);
FORCEPROP 2 LAST PACK_TYPE C0201
J 2
(-7100 1850);
DISPLAY 0.553191 (-7100 1850);
DISPLAY INVISIBLE (-7100 1850);
FORCEPROP 1 LAST MATERIAL X6S
J 2
(-6916 1879);
DISPLAY 0.574468 (-6916 1879);
PAINT GREEN (-6916 1879);
DISPLAY INVISIBLE (-6916 1879);
FORCEPROP 2 LAST VOLTAGE 6.3V
J 2
(-7275 1850);
DISPLAY 0.553191 (-7275 1850);
DISPLAY INVISIBLE (-7275 1850);
FORCEPROP 1 LAST PIN_NAMES_ROTATE TRUE
J 2
(-6925 1800);
DISPLAY 0.489362 (-6925 1800);
PAINT GREEN (-6925 1800);
DISPLAY INVISIBLE (-6925 1800);
FORCEPROP 2 LAST CDS_LIB pure_quanta
J 2
(-6925 1800);
DISPLAY INVISIBLE (-6925 1800);
FORCEPROP 1 LAST CDS_LMAN_SYM_OUTLINE -25,50,25,-50
J 2
(-6925 1800);
DISPLAY 0.468085 (-6925 1800);
PAINT GREEN (-6925 1800);
DISPLAY INVISIBLE (-6925 1800);
FORCEPROP 1 LAST PATH I96
J 2
(-6925 1800);
DISPLAY 0.723404 (-6925 1800);
DISPLAY INVISIBLE (-6925 1800);
FORCEPROP 1 LAST PART_NUMBER SP_CH4221MEE01
J 2
(-7041 1888);
DISPLAY 0.574468 (-7041 1888);
PAINT GREEN (-7041 1888);
DISPLAY INVISIBLE (-7041 1888);
FORCEPROP 1 LAST LOCATION C6553
J 0
(-6675 1875);
DISPLAY 1.021277 (-6675 1875);
DISPLAY INVISIBLE (-6675 1875);
FORCEADD Q_CAP_DIFFBUS..2
R 2
(-6925 1750);
FORCEPROP 1 LAST LOCATION C6554
J 2
(-6650 1750);
DISPLAY 0.723404 (-6650 1750);
PAINT GREEN (-6650 1750);
FORCEPROP 2 LAST $SEC 1
J 2
(-6750 1825);
DISPLAY 0.680851 (-6750 1825);
PAINT MONO (-6750 1825);
DISPLAY INVISIBLE (-6750 1825);
FORCEPROP 2 LAST CDS_SEC 1
J 2
(-6750 1825);
DISPLAY 0.680851 (-6750 1825);
DISPLAY INVISIBLE (-6750 1825);
FORCEPROP 2 LASTPIN (-6850 1750) $PN 1
J 0
(-6840 1760);
DISPLAY 0.808511 (-6840 1760);
FORCEPROP 2 LASTPIN (-7000 1750) $PN 2
J 2
(-7010 1760);
DISPLAY 0.808511 (-7010 1760);
FORCEPROP 2 LAST VALUE DIFF BUS_0.22UF
J 2
(-7075 1750);
DISPLAY 0.553191 (-7075 1750);
FORCEPROP 2 LAST TOLERANCE 20%
J 2
(-7000 1800);
DISPLAY 0.553191 (-7000 1800);
DISPLAY INVISIBLE (-7000 1800);
FORCEPROP 2 LAST PACK_TYPE C0201
J 2
(-7100 1800);
DISPLAY 0.553191 (-7100 1800);
DISPLAY INVISIBLE (-7100 1800);
FORCEPROP 1 LAST MATERIAL X6S
J 2
(-6916 1829);
DISPLAY 0.574468 (-6916 1829);
PAINT GREEN (-6916 1829);
DISPLAY INVISIBLE (-6916 1829);
FORCEPROP 2 LAST VOLTAGE 6.3V
J 2
(-7275 1800);
DISPLAY 0.553191 (-7275 1800);
DISPLAY INVISIBLE (-7275 1800);
FORCEPROP 1 LAST PIN_NAMES_ROTATE TRUE
J 2
(-6925 1750);
DISPLAY 0.489362 (-6925 1750);
PAINT GREEN (-6925 1750);
DISPLAY INVISIBLE (-6925 1750);
FORCEPROP 2 LAST CDS_LIB pure_quanta
J 2
(-6925 1750);
DISPLAY INVISIBLE (-6925 1750);
FORCEPROP 1 LAST CDS_LMAN_SYM_OUTLINE -25,50,25,-50
J 2
(-6925 1750);
DISPLAY 0.468085 (-6925 1750);
PAINT GREEN (-6925 1750);
DISPLAY INVISIBLE (-6925 1750);
FORCEPROP 1 LAST PATH I97
J 2
(-6925 1750);
DISPLAY 0.723404 (-6925 1750);
DISPLAY INVISIBLE (-6925 1750);
FORCEPROP 1 LAST PART_NUMBER SP_CH4221MEE01
J 2
(-7041 1838);
DISPLAY 0.574468 (-7041 1838);
PAINT GREEN (-7041 1838);
DISPLAY INVISIBLE (-7041 1838);
FORCEPROP 1 LAST LOCATION C6554
J 0
(-6675 1825);
DISPLAY 1.021277 (-6675 1825);
DISPLAY INVISIBLE (-6675 1825);
FORCEADD TAP..1
R 2
(-7900 1950);
FORCEPROP 3 LASTPIN (-7850 1950) SIG_NAME P5E_CPU0_P1_TX_BUF_DN<9>
J 0
(-7840 1960);
DISPLAY 0.659574 (-7840 1960);
PAINT MONO (-7840 1960);
DISPLAY INVISIBLE (-7840 1960);
FORCEPROP 1 LASTPIN (-7850 1950) BN 9
J 2
(-7838 1958);
DISPLAY 0.680851 (-7838 1958);
PAINT GREEN (-7838 1958);
FORCEPROP 2 LAST CDS_LIB standard
J 0
(-7900 1950);
DISPLAY INVISIBLE (-7900 1950);
FORCEPROP 1 LAST BODY_TYPE PLUMBING
J 2
(-7900 2000);
DISPLAY 0.872340 (-7900 2000);
PAINT GREEN (-7900 2000);
DISPLAY INVISIBLE (-7900 2000);
FORCEPROP 1 LAST HDL_TAP TRUE
J 2
(-8225 1825);
DISPLAY 0.872340 (-8225 1825);
DISPLAY INVISIBLE (-8225 1825);
FORCEPROP 1 LAST PATH I98
J 2
(-7898 1950);
DISPLAY 0.872340 (-7898 1950);
PAINT GREEN (-7898 1950);
DISPLAY INVISIBLE (-7898 1950);
FORCEADD TAP..1
R 2
(-7900 2150);
FORCEPROP 3 LASTPIN (-7850 2150) SIG_NAME P5E_CPU0_P1_TX_BUF_DN<8>
J 0
(-7840 2160);
DISPLAY 0.659574 (-7840 2160);
PAINT MONO (-7840 2160);
DISPLAY INVISIBLE (-7840 2160);
FORCEPROP 1 LASTPIN (-7850 2150) BN 8
J 2
(-7838 2158);
DISPLAY 0.680851 (-7838 2158);
PAINT GREEN (-7838 2158);
FORCEPROP 2 LAST CDS_LIB standard
J 0
(-7900 2150);
DISPLAY INVISIBLE (-7900 2150);
FORCEPROP 1 LAST BODY_TYPE PLUMBING
J 2
(-7900 2200);
DISPLAY 0.872340 (-7900 2200);
PAINT GREEN (-7900 2200);
DISPLAY INVISIBLE (-7900 2200);
FORCEPROP 1 LAST HDL_TAP TRUE
J 2
(-8225 2025);
DISPLAY 0.872340 (-8225 2025);
DISPLAY INVISIBLE (-8225 2025);
FORCEPROP 1 LAST PATH I99
J 2
(-7898 2150);
DISPLAY 0.872340 (-7898 2150);
PAINT GREEN (-7898 2150);
DISPLAY INVISIBLE (-7898 2150);
FORCEADD QUANTA_TITLE_BLOCK_C..1
(0 0);
FORCEPROP 0 LAST CDS_CON_LAST_MODIFIED Thu Sep 14 16:12:52 2023
J 0
(-1885 15);
DISPLAY INVISIBLE (-1885 15);
FORCEPROP 1 LAST CUSTOM_TXT_CDS <CON_LAST_MODIFIED>
J 0
(-1885 15);
DISPLAY 0.978723 (-1885 15);
FORCEPROP 2 LAST CUSTOM_TXT_CDS <XR_PAGE_TITLE>
J 0
(-7890 5250);
DISPLAY 0.638298 (-7890 5250);
PAINT PINK (-7890 5250);
DISPLAY INVISIBLE (-7890 5250);
FORCEPROP 1 LAST CUSTOM_TXT_CDS <NAME_2>
J 0
(-3175 50);
FORCEPROP 1 LAST CUSTOM_TXT_CDS <NAME_1>
J 0
(-3175 175);
FORCEPROP 1 LAST CUSTOM_TXT_CDS <Q_NUMBER>
J 0
(-1403 103);
DISPLAY 1.212766 (-1403 103);
FORCEPROP 1 LAST CUSTOM_TXT_CDS <Q_PROJ>
J 0
(-2382 102);
DISPLAY 1.212766 (-2382 102);
FORCEPROP 1 LAST CUSTOM_TXT_CDS <Q_REV>
J 0
(-184 103);
DISPLAY 1.212766 (-184 103);
FORCEPROP 1 LAST CUSTOM_TXT_CDS <CON_PAGE_NUM> OF <CON_TOTAL_PAGES>
J 0
(-446 18);
DISPLAY 0.978723 (-446 18);
FORCEPROP 1 LAST Q_TITLE RETIMER_CPU0_P1(4)
J 0
(-9366 26);
DISPLAY 2.446809 (-9366 26);
PAINT GREEN (-9366 26);
FORCEPROP 1 LAST CDS_LMAN_SYM_OUTLINE -9475,6775,100,-125
J 0
(0 0);
DISPLAY 0.468085 (0 0);
PAINT GREEN (0 0);
DISPLAY INVISIBLE (0 0);
FORCEPROP 2 LAST CDS_LIB pure_quanta
J 0
(0 0);
DISPLAY INVISIBLE (0 0);
FORCEPROP 2 LAST PAGE_BORDER TRUE
J 0
(-7890 5250);
DISPLAY 0.638298 (-7890 5250);
PAINT PINK (-7890 5250);
DISPLAY INVISIBLE (-7890 5250);
FORCEPROP 2 LAST CDS_XR_PAGE_TITLE CR-287 : @T6G_MB_LIB.T6G(SCH_1):PAGE287
J 0
(-7890 5250);
DISPLAY 0.638298 (-7890 5250);
PAINT PINK (-7890 5250);
DISPLAY INVISIBLE (-7890 5250);
FORCEPROP 1 LAST Q_DEPT BU9
J 1
(-3763 49);
DISPLAY 1.957447 (-3763 49);
PAINT GREEN (-3763 49);
DISPLAY INVISIBLE (-3763 49);
FORCEPROP 1 LAST COMMENT_BODY TRUE
J 0
(12 -13);
DISPLAY 0.978723 (12 -13);
PAINT GREEN (12 -13);
DISPLAY INVISIBLE (12 -13);
WIRE 17 -1 (-1600 2175)(-700 2175);
FORCEPROP 2 LAST SIG_NAME P5E_CPU0_P1_TX_BUF_C_DN<7:0>
J 0
(-1610 2185);
DISPLAY 0.680851 (-1610 2185);
PAINT WHITE (-1610 2185);
WIRE 17 -1 (-1800 2225)(-700 2225);
FORCEPROP 2 LAST SIG_NAME P5E_CPU0_P1_TX_BUF_C_DP<7:0>
J 0
(-1610 2235);
DISPLAY 0.680851 (-1610 2235);
PAINT WHITE (-1610 2235);
WIRE 17 -1 (-3425 775)(-3425 975);
WIRE 17 -1 (-3425 975)(-3425 1175);
WIRE 17 -1 (-3425 1175)(-3425 1375);
WIRE 17 -1 (-3425 1375)(-3425 1575);
WIRE 17 -1 (-3425 1575)(-3425 1775);
WIRE 17 -1 (-3425 1775)(-3425 1975);
WIRE 17 -1 (-3425 1975)(-3425 2175);
WIRE 17 -1 (-4275 2175)(-3425 2175);
FORCEPROP 2 LAST SIG_NAME P5E_CPU0_P1_TX_BUF_DN<7:0>
J 0
(-4260 2185);
DISPLAY 0.680851 (-4260 2185);
PAINT WHITE (-4260 2185);
WIRE 17 -1 (-3175 1025)(-3175 825);
WIRE 17 -1 (-3175 1225)(-3175 1025);
WIRE 17 -1 (-3175 1425)(-3175 1225);
WIRE 17 -1 (-3175 1425)(-3175 1625);
WIRE 17 -1 (-3175 1825)(-3175 1625);
WIRE 17 -1 (-3175 2025)(-3175 1825);
WIRE 17 -1 (-3175 2225)(-3175 2025);
WIRE 17 -1 (-4275 2225)(-3175 2225);
FORCEPROP 2 LAST SIG_NAME P5E_CPU0_P1_TX_BUF_DP<7:0>
J 0
(-4260 2235);
DISPLAY 0.680851 (-4260 2235);
PAINT WHITE (-4260 2235);
WIRE 17 -1 (-1800 1025)(-1800 825);
WIRE 17 -1 (-1800 1225)(-1800 1025);
WIRE 17 -1 (-1800 1425)(-1800 1225);
WIRE 17 -1 (-1800 1425)(-1800 1625);
WIRE 17 -1 (-1800 1825)(-1800 1625);
WIRE 17 -1 (-1800 2025)(-1800 1825);
WIRE 17 -1 (-1800 2225)(-1800 2025);
WIRE 17 -1 (-1600 975)(-1600 775);
WIRE 17 -1 (-1600 1175)(-1600 975);
WIRE 17 -1 (-1600 1375)(-1600 1175);
WIRE 17 -1 (-1600 1375)(-1600 1575);
WIRE 17 -1 (-1600 1775)(-1600 1575);
WIRE 17 -1 (-1600 1975)(-1600 1775);
WIRE 17 -1 (-1600 2175)(-1600 1975);
WIRE 17 -1 (-6125 1775)(-6125 1575);
WIRE 17 -1 (-6125 1975)(-6125 1775);
WIRE 17 -1 (-6125 1375)(-6125 1575);
WIRE 17 -1 (-6125 1375)(-6125 1175);
WIRE 17 -1 (-6125 2175)(-6125 1975);
FORCEPROP 2 LAST SIG_NAME P5E_CPU0_P1_TX_BUF_C_DN<15:8>
J 0
(-6135 2185);
DISPLAY 0.680851 (-6135 2185);
PAINT WHITE (-6135 2185);
WIRE 17 -1 (-6325 2025)(-6325 1825);
WIRE 17 -1 (-6325 2225)(-6325 2025);
WIRE 17 -1 (-6325 1825)(-6325 1625);
WIRE 17 -1 (-6325 1425)(-6325 1625);
WIRE 17 -1 (-6325 2225)(-5225 2225);
FORCEPROP 2 LAST SIG_NAME P5E_CPU0_P1_TX_BUF_C_DP<15:8>
J 0
(-6135 2235);
DISPLAY 0.680851 (-6135 2235);
PAINT WHITE (-6135 2235);
WIRE 17 -1 (-7950 775)(-7950 975);
WIRE 17 -1 (-7950 975)(-7950 1175);
WIRE 17 -1 (-7950 1175)(-7950 1375);
WIRE 17 -1 (-7950 1375)(-7950 1575);
WIRE 17 -1 (-7950 1575)(-7950 1775);
WIRE 17 -1 (-7950 1775)(-7950 1975);
WIRE 17 -1 (-7950 1975)(-7950 2175);
WIRE 17 -1 (-8800 2175)(-7950 2175);
FORCEPROP 2 LAST SIG_NAME P5E_CPU0_P1_TX_BUF_DN<15:8>
J 0
(-8785 2185);
DISPLAY 0.680851 (-8785 2185);
PAINT WHITE (-8785 2185);
WIRE 17 -1 (-7700 1025)(-7700 825);
WIRE 17 -1 (-7700 1225)(-7700 1025);
WIRE 17 -1 (-7700 1425)(-7700 1225);
WIRE 17 -1 (-7700 1425)(-7700 1625);
WIRE 17 -1 (-7700 1825)(-7700 1625);
WIRE 17 -1 (-7700 2025)(-7700 1825);
WIRE 17 -1 (-7700 2225)(-7700 2025);
WIRE 17 -1 (-8800 2225)(-7700 2225);
FORCEPROP 2 LAST SIG_NAME P5E_CPU0_P1_TX_BUF_DP<15:8>
J 0
(-8785 2235);
DISPLAY 0.680851 (-8785 2235);
PAINT WHITE (-8785 2235);
WIRE 17 -1 (-6125 975)(-6125 775);
WIRE 17 -1 (-6125 1175)(-6125 975);
WIRE 17 -1 (-6325 1025)(-6325 825);
WIRE 17 -1 (-6325 1225)(-6325 1025);
WIRE 17 -1 (-6325 1425)(-6325 1225);
WIRE 17 -1 (-1625 4325)(-1625 4675);
WIRE 17 -1 (-1625 4325)(-1625 3975);
WIRE 17 -1 (-1625 5025)(-1625 4675);
WIRE 17 -1 (-1625 5375)(-1625 5025);
WIRE 17 -1 (-1625 3975)(-1625 3625);
WIRE 17 -1 (-1625 3625)(-1625 3275);
WIRE 17 -1 (-1625 5725)(-1625 5375);
FORCEPROP 2 LAST SIG_NAME P5E_CPU0_P1_TX_BUF_DN<7:0>
J 0
(-1635 5735);
DISPLAY 0.680851 (-1635 5735);
PAINT WHITE (-1635 5735);
WIRE 17 -1 (-1825 4425)(-1825 4075);
WIRE 17 -1 (-1825 4425)(-1825 4775);
WIRE 17 -1 (-1825 4075)(-1825 3725);
WIRE 17 -1 (-1825 3725)(-1825 3375);
WIRE 17 -1 (-1825 5125)(-1825 4775);
WIRE 17 -1 (-1825 5475)(-1825 5125);
WIRE 17 -1 (-1825 5825)(-1825 5475);
WIRE 17 -1 (-1825 5825)(-725 5825);
FORCEPROP 2 LAST SIG_NAME P5E_CPU0_P1_TX_BUF_DP<7:0>
J 0
(-1635 5835);
DISPLAY 0.680851 (-1635 5835);
PAINT WHITE (-1635 5835);
WIRE 17 -1 (-6800 3650)(-6800 3300);
WIRE 17 -1 (-6800 4000)(-6800 3650);
WIRE 17 -1 (-6800 4350)(-6800 4000);
WIRE 17 -1 (-6800 4350)(-6800 4700);
WIRE 17 -1 (-6800 5050)(-6800 4700);
WIRE 17 -1 (-6800 5400)(-6800 5050);
WIRE 17 -1 (-6800 5750)(-6800 5400);
FORCEPROP 2 LAST SIG_NAME P5E_CPU0_P1_TX_BUF_DN<15:8>
J 0
(-6810 5760);
DISPLAY 0.680851 (-6810 5760);
PAINT WHITE (-6810 5760);
WIRE 17 -1 (-7000 5150)(-7000 4800);
WIRE 17 -1 (-7000 5500)(-7000 5150);
WIRE 17 -1 (-7000 4450)(-7000 4800);
WIRE 17 -1 (-7000 4450)(-7000 4100);
WIRE 17 -1 (-7000 5850)(-7000 5500);
WIRE 17 -1 (-7000 5850)(-5900 5850);
FORCEPROP 2 LAST SIG_NAME P5E_CPU0_P1_TX_BUF_DP<15:8>
J 0
(-6810 5860);
DISPLAY 0.680851 (-6810 5860);
PAINT WHITE (-6810 5860);
WIRE 17 -1 (-7000 4100)(-7000 3750);
WIRE 17 -1 (-7000 3750)(-7000 3400);
WIRE 17 -1 (-6125 2175)(-5225 2175);
WIRE 17 -1 (-1625 5725)(-750 5725);
WIRE 17 -1 (-6800 5750)(-5925 5750);
WIRE 16 -1 (-7325 3725)(-7100 3725);
WIRE 16 -1 (-7325 5475)(-7100 5475);
WIRE 16 -1 (-7325 5375)(-6900 5375);
WIRE 16 -1 (-7325 5125)(-7100 5125);
WIRE 16 -1 (-7325 4425)(-7100 4425);
WIRE 16 -1 (-7325 4675)(-6900 4675);
WIRE 16 -1 (-2150 3250)(-1725 3250);
WIRE 16 -1 (-2150 3600)(-1725 3600);
WIRE 16 -1 (-2150 5100)(-1925 5100);
WIRE 16 -1 (-2150 4400)(-1925 4400);
WIRE 16 -1 (-2150 4650)(-1725 4650);
WIRE 16 -1 (-2150 5000)(-1725 5000);
WIRE 16 -1 (-2150 5450)(-1925 5450);
WIRE 16 -1 (-7325 5025)(-6900 5025);
WIRE 16 -1 (-2150 5800)(-1925 5800);
WIRE 16 -1 (-2150 4750)(-1925 4750);
WIRE 16 -1 (-2150 3700)(-1925 3700);
WIRE 16 -1 (-7325 5725)(-6900 5725);
WIRE 16 -1 (-7325 5825)(-7100 5825);
WIRE 16 -1 (-7325 3375)(-7100 3375);
WIRE 16 -1 (-7325 3625)(-6900 3625);
WIRE 16 -1 (-7325 3975)(-6900 3975);
WIRE 16 -1 (-7325 4075)(-7100 4075);
WIRE 16 -1 (-7325 4325)(-6900 4325);
WIRE 16 -1 (-7325 4775)(-7100 4775);
WIRE 16 -1 (-7325 3275)(-6900 3275);
WIRE 16 -1 (-2150 5700)(-1725 5700);
WIRE 16 -1 (-2150 3350)(-1925 3350);
WIRE 16 -1 (-2150 3950)(-1725 3950);
WIRE 16 -1 (-2150 4050)(-1925 4050);
WIRE 16 -1 (-2150 5350)(-1725 5350);
WIRE 16 -1 (-2150 4300)(-1725 4300);
WIRE 16 -1 (-6850 2150)(-6225 2150);
WIRE 16 -1 (-6850 2200)(-6425 2200);
WIRE 16 -1 (-7000 2200)(-7600 2200);
WIRE 16 -1 (-7000 2150)(-7850 2150);
WIRE 16 -1 (-6850 2000)(-6425 2000);
WIRE 16 -1 (-6850 1950)(-6225 1950);
WIRE 16 -1 (-6850 1600)(-6425 1600);
WIRE 16 -1 (-6850 1550)(-6225 1550);
WIRE 16 -1 (-6850 1400)(-6425 1400);
WIRE 16 -1 (-6850 1350)(-6225 1350);
WIRE 16 -1 (-6850 1200)(-6425 1200);
WIRE 16 -1 (-6850 1150)(-6225 1150);
WIRE 16 -1 (-6850 1000)(-6425 1000);
WIRE 16 -1 (-6850 950)(-6225 950);
WIRE 16 -1 (-6850 800)(-6425 800);
WIRE 16 -1 (-6850 750)(-6225 750);
WIRE 16 -1 (-7000 2000)(-7600 2000);
WIRE 16 -1 (-7000 1800)(-7600 1800);
WIRE 16 -1 (-7000 1600)(-7600 1600);
WIRE 16 -1 (-7000 1750)(-7850 1750);
WIRE 16 -1 (-7000 1950)(-7850 1950);
WIRE 16 -1 (-7000 1400)(-7600 1400);
WIRE 16 -1 (-7000 1200)(-7600 1200);
WIRE 16 -1 (-7000 1150)(-7850 1150);
WIRE 16 -1 (-7000 1350)(-7850 1350);
WIRE 16 -1 (-7000 1550)(-7850 1550);
WIRE 16 -1 (-7000 1000)(-7600 1000);
WIRE 16 -1 (-7000 800)(-7600 800);
WIRE 16 -1 (-7000 950)(-7850 950);
WIRE 16 -1 (-7000 750)(-7850 750);
WIRE 16 -1 (-6850 1800)(-6425 1800);
WIRE 16 -1 (-6850 1750)(-6225 1750);
WIRE 16 -1 (-2325 1950)(-1700 1950);
WIRE 16 -1 (-2325 2000)(-1900 2000);
WIRE 16 -1 (-2325 1800)(-1900 1800);
WIRE 16 -1 (-2325 1750)(-1700 1750);
WIRE 16 -1 (-2325 1600)(-1900 1600);
WIRE 16 -1 (-2325 1550)(-1700 1550);
WIRE 16 -1 (-2475 2200)(-3075 2200);
WIRE 16 -1 (-2475 2000)(-3075 2000);
WIRE 16 -1 (-2475 1800)(-3075 1800);
WIRE 16 -1 (-2475 1600)(-3075 1600);
WIRE 16 -1 (-2325 1400)(-1900 1400);
WIRE 16 -1 (-2475 1400)(-3075 1400);
WIRE 16 -1 (-2325 1350)(-1700 1350);
WIRE 16 -1 (-2325 1150)(-1700 1150);
WIRE 16 -1 (-2325 1200)(-1900 1200);
WIRE 16 -1 (-2325 1000)(-1900 1000);
WIRE 16 -1 (-2325 950)(-1700 950);
WIRE 16 -1 (-2325 750)(-1700 750);
WIRE 16 -1 (-2325 800)(-1900 800);
WIRE 16 -1 (-2475 1200)(-3075 1200);
WIRE 16 -1 (-2475 1000)(-3075 1000);
WIRE 16 -1 (-2475 800)(-3075 800);
WIRE 16 -1 (-2475 2150)(-3325 2150);
WIRE 16 -1 (-2475 1950)(-3325 1950);
WIRE 16 -1 (-2475 1750)(-3325 1750);
WIRE 16 -1 (-2475 1550)(-3325 1550);
WIRE 16 -1 (-2475 1350)(-3325 1350);
WIRE 16 -1 (-2475 1150)(-3325 1150);
WIRE 16 -1 (-2475 950)(-3325 950);
WIRE 16 -1 (-2475 750)(-3325 750);
WIRE 16 -1 (-2325 2200)(-1900 2200);
WIRE 16 -1 (-2325 2150)(-1700 2150);
FORCENOTE
RETIMER TO EXAMAX
(-3675 2900) 0;
DISPLAY LEFT (-3675 2900);
DISPLAY 3.148936 (-3675 2900);
FORCENOTE
RETIMER TO EXAMAX
(-8675 2925) 0;
DISPLAY LEFT (-8675 2925);
DISPLAY 3.148936 (-8675 2925);
FORCENOTE
P5E_CPU0_P1_TX_BUF_DP/DN<0-15> LANE REVERSAL
(-9050 6500) 0;
DISPLAY LEFT (-9050 6500);
DISPLAY 1.595745 (-9050 6500);
QUIT
